FILE_TYPE = MACRO_DRAWING;
SET COLOR_WIRE YELLOW;
SET COLOR_PROP ORANGE;
SET COLOR_DOT WHITE;
SET COLOR_ARC YELLOW;
SET COLOR_BODY GREEN;
SET COLOR_NOTE PURPLE;
SET PROP_DISPLAY VALUE;
SET PAGE_NUMBER P148;
FORCEADD Q_RES..2
(-2875 6050);
FORCEPROP 1 LAST LOCATION R1734
J 0
(-2830 6175);
DISPLAY 0.489362 (-2830 6175);
PAINT SKYBLUE (-2830 6175);
FORCEPROP 0 LAST $SEC 1
J 0
(-2825 6225);
PAINT MONO (-2825 6225);
DISPLAY INVISIBLE (-2825 6225);
FORCEPROP 0 LAST CDS_SEC 1
J 0
(-2825 6225);
PAINT MONO (-2825 6225);
DISPLAY INVISIBLE (-2825 6225);
FORCEPROP 1 LASTPIN (-2875 6150) $PN 1
J 0
(-2870 6112);
DISPLAY 0.489362 (-2870 6112);
PAINT GREEN (-2870 6112);
FORCEPROP 1 LASTPIN (-2875 5950) $PN 2
J 0
(-2870 5960);
DISPLAY 0.489362 (-2870 5960);
PAINT GREEN (-2870 5960);
FORCEPROP 1 LAST WATTAGE 1/16W
J 0
(-2835 6025);
DISPLAY 0.489362 (-2835 6025);
PAINT SKYBLUE (-2835 6025);
FORCEPROP 1 LAST MATERIAL CHIP
J 0
(-2835 5975);
DISPLAY 0.489362 (-2835 5975);
PAINT SKYBLUE (-2835 5975);
FORCEPROP 1 LAST TOLERANCE 1%
J 0
(-2830 6075);
DISPLAY 0.489362 (-2830 6075);
PAINT SKYBLUE (-2830 6075);
FORCEPROP 1 LAST VALUE 10K
J 0
(-2830 6125);
DISPLAY 0.489362 (-2830 6125);
PAINT SKYBLUE (-2830 6125);
FORCEPROP 1 LAST PART_NUMBER CS31002FB08
J 0
(-2835 5925);
DISPLAY 0.489362 (-2835 5925);
PAINT SKYBLUE (-2835 5925);
FORCEPROP 1 LAST PACK_TYPE 0402LF
J 0
(-2835 5875);
DISPLAY 0.489362 (-2835 5875);
PAINT SKYBLUE (-2835 5875);
FORCEPROP 2 LAST CDS_LIB pure_quanta
J 0
(-2875 6050);
PAINT MONO (-2875 6050);
DISPLAY INVISIBLE (-2875 6050);
FORCEPROP 1 LAST PATH I244
J 0
(-2825 6225);
DISPLAY 0.978723 (-2825 6225);
PAINT WHITE (-2825 6225);
DISPLAY INVISIBLE (-2825 6225);
FORCEADD Q_RES..2
(-3125 6050);
FORCEPROP 1 LAST LOCATION R1731
J 0
(-3080 6175);
DISPLAY 0.489362 (-3080 6175);
PAINT SKYBLUE (-3080 6175);
FORCEPROP 2 LAST $SEC 1
J 0
(-3075 6275);
DISPLAY 0.680851 (-3075 6275);
PAINT MONO (-3075 6275);
DISPLAY INVISIBLE (-3075 6275);
FORCEPROP 2 LAST CDS_SEC 1
J 0
(-3075 6275);
DISPLAY 0.680851 (-3075 6275);
DISPLAY INVISIBLE (-3075 6275);
FORCEPROP 1 LASTPIN (-3125 6150) $PN 1
J 0
(-3120 6112);
DISPLAY 0.489362 (-3120 6112);
FORCEPROP 1 LASTPIN (-3125 5950) $PN 2
J 0
(-3120 5960);
DISPLAY 0.489362 (-3120 5960);
FORCEPROP 1 LAST WATTAGE 1/16W
J 0
(-3085 6025);
DISPLAY 0.489362 (-3085 6025);
PAINT SKYBLUE (-3085 6025);
FORCEPROP 1 LAST MATERIAL CHIP
J 0
(-3085 5975);
DISPLAY 0.489362 (-3085 5975);
PAINT SKYBLUE (-3085 5975);
FORCEPROP 1 LAST TOLERANCE 1%
J 0
(-3080 6075);
DISPLAY 0.489362 (-3080 6075);
PAINT SKYBLUE (-3080 6075);
FORCEPROP 1 LAST VALUE 10K
J 0
(-3080 6125);
DISPLAY 0.489362 (-3080 6125);
PAINT SKYBLUE (-3080 6125);
FORCEPROP 1 LAST PACK_TYPE 0402LF
J 0
(-3075 5925);
DISPLAY 0.489362 (-3075 5925);
PAINT SKYBLUE (-3075 5925);
FORCEPROP 2 LAST CDS_LIB pure_quanta
J 0
(-3125 6050);
DISPLAY INVISIBLE (-3125 6050);
FORCEPROP 1 LAST PATH I245
J 0
(-3075 6225);
DISPLAY 0.978723 (-3075 6225);
PAINT WHITE (-3075 6225);
DISPLAY INVISIBLE (-3075 6225);
FORCEPROP 1 LAST PART_NUMBER CS31002FB08
J 0
(-3085 5925);
DISPLAY 0.617021 (-3085 5925);
PAINT SKYBLUE (-3085 5925);
DISPLAY INVISIBLE (-3085 5925);
FORCEADD Q_RES..2
(-2875 5550);
FORCEPROP 1 LAST LOCATION R1735
J 0
(-2825 5575);
DISPLAY 0.489362 (-2825 5575);
PAINT SKYBLUE (-2825 5575);
FORCEPROP 2 LAST $SEC 1
J 0
(-2825 5775);
DISPLAY 0.680851 (-2825 5775);
PAINT MONO (-2825 5775);
DISPLAY INVISIBLE (-2825 5775);
FORCEPROP 2 LAST CDS_SEC 1
J 0
(-2825 5775);
DISPLAY 0.680851 (-2825 5775);
DISPLAY INVISIBLE (-2825 5775);
FORCEPROP 1 LASTPIN (-2875 5650) $PN 1
J 0
(-2870 5612);
DISPLAY 0.489362 (-2870 5612);
FORCEPROP 1 LASTPIN (-2875 5450) $PN 2
J 0
(-2870 5460);
DISPLAY 0.489362 (-2870 5460);
FORCEPROP 1 LAST MATERIAL EMPTY
J 0
(-2825 5425);
DISPLAY 0.489362 (-2825 5425);
PAINT RED (-2825 5425);
FORCEPROP 1 LAST TOLERANCE 1%
J 0
(-2825 5475);
DISPLAY 0.489362 (-2825 5475);
PAINT SKYBLUE (-2825 5475);
FORCEPROP 1 LAST VALUE 10K
J 0
(-2825 5525);
DISPLAY 0.489362 (-2825 5525);
PAINT SKYBLUE (-2825 5525);
FORCEPROP 2 LAST CDS_LIB pure_quanta
J 0
(-2875 5550);
DISPLAY INVISIBLE (-2875 5550);
FORCEPROP 1 LAST PATH I246
J 0
(-2825 5725);
DISPLAY 0.978723 (-2825 5725);
PAINT WHITE (-2825 5725);
DISPLAY INVISIBLE (-2825 5725);
FORCEPROP 1 LAST WATTAGE 1/16W
J 0
(-2835 5525);
DISPLAY 0.978723 (-2835 5525);
PAINT SKYBLUE (-2835 5525);
DISPLAY INVISIBLE (-2835 5525);
FORCEPROP 1 LAST PART_NUMBER CS31002FB08
J 0
(-2835 5425);
DISPLAY 0.978723 (-2835 5425);
PAINT SKYBLUE (-2835 5425);
DISPLAY INVISIBLE (-2835 5425);
FORCEPROP 1 LAST PACK_TYPE 0402LF
J 0
(-2835 5375);
DISPLAY 0.978723 (-2835 5375);
PAINT SKYBLUE (-2835 5375);
DISPLAY INVISIBLE (-2835 5375);
FORCEADD UNIVERSAL_GND..1
(-2875 5325);
FORCEPROP 3 LASTPIN (-2875 5375) SIG_NAME GND\g
J 0
(-2865 5385);
DISPLAY 0.659574 (-2865 5385);
PAINT MONO (-2865 5385);
DISPLAY INVISIBLE (-2865 5385);
FORCEPROP 2 LAST CDS_LIB pure_quanta_power
J 0
(-2875 5325);
DISPLAY INVISIBLE (-2875 5325);
FORCEPROP 1 LAST PATH I247
J 0
(-2800 5325);
DISPLAY 0.872340 (-2800 5325);
PAINT AQUA (-2800 5325);
DISPLAY INVISIBLE (-2800 5325);
FORCEPROP 1 LAST HDL_POWER GND
J 1
(-2850 5250);
DISPLAY 0.872340 (-2850 5250);
PAINT GREEN (-2850 5250);
DISPLAY INVISIBLE (-2850 5250);
FORCEADD UNIVERSAL_POWER..1
(-3525 6400);
FORCEPROP 3 LASTPIN (-3525 6350) SIG_NAME P3V3_STBY\g
J 0
(-3515 6360);
DISPLAY 0.659574 (-3515 6360);
PAINT MONO (-3515 6360);
DISPLAY INVISIBLE (-3515 6360);
FORCEPROP 1 LAST HDL_POWER P3V3_STBY
J 1
(-3525 6450);
DISPLAY 0.489362 (-3525 6450);
PAINT GREEN (-3525 6450);
FORCEPROP 2 LAST CDS_LIB pure_quanta_power
J 0
(-3525 6400);
DISPLAY INVISIBLE (-3525 6400);
FORCEPROP 1 LAST PATH I248
J 0
(-3475 6425);
DISPLAY 0.872340 (-3475 6425);
PAINT AQUA (-3475 6425);
DISPLAY INVISIBLE (-3475 6425);
FORCEADD Q_RES..2
(-3325 6050);
FORCEPROP 1 LAST LOCATION R1728
J 0
(-3275 6175);
DISPLAY 0.489362 (-3275 6175);
PAINT SKYBLUE (-3275 6175);
FORCEPROP 2 LAST $SEC 1
J 0
(-3275 6275);
DISPLAY 0.680851 (-3275 6275);
PAINT MONO (-3275 6275);
DISPLAY INVISIBLE (-3275 6275);
FORCEPROP 2 LAST CDS_SEC 1
J 0
(-3275 6275);
DISPLAY 0.680851 (-3275 6275);
DISPLAY INVISIBLE (-3275 6275);
FORCEPROP 1 LASTPIN (-3325 6150) $PN 1
J 0
(-3320 6112);
DISPLAY 0.489362 (-3320 6112);
FORCEPROP 1 LASTPIN (-3325 5950) $PN 2
J 0
(-3320 5960);
DISPLAY 0.489362 (-3320 5960);
FORCEPROP 1 LAST TOLERANCE 1%
J 0
(-3275 6075);
DISPLAY 0.489362 (-3275 6075);
PAINT SKYBLUE (-3275 6075);
FORCEPROP 1 LAST VALUE 10K
J 0
(-3275 6125);
DISPLAY 0.489362 (-3275 6125);
PAINT SKYBLUE (-3275 6125);
FORCEPROP 2 LAST CDS_LIB pure_quanta
J 0
(-3325 6050);
DISPLAY INVISIBLE (-3325 6050);
FORCEPROP 1 LAST PATH I249
J 0
(-3275 6225);
DISPLAY 0.978723 (-3275 6225);
PAINT WHITE (-3275 6225);
DISPLAY INVISIBLE (-3275 6225);
FORCEPROP 1 LAST WATTAGE 1/16W
J 0
(-3285 6025);
DISPLAY 0.978723 (-3285 6025);
PAINT SKYBLUE (-3285 6025);
DISPLAY INVISIBLE (-3285 6025);
FORCEPROP 1 LAST MATERIAL CHIP
J 0
(-3285 5975);
DISPLAY 0.978723 (-3285 5975);
PAINT SKYBLUE (-3285 5975);
DISPLAY INVISIBLE (-3285 5975);
FORCEPROP 1 LAST PART_NUMBER CS31002FB08
J 0
(-3285 5925);
DISPLAY 0.978723 (-3285 5925);
PAINT SKYBLUE (-3285 5925);
DISPLAY INVISIBLE (-3285 5925);
FORCEPROP 1 LAST PACK_TYPE 0402LF
J 0
(-3285 5875);
DISPLAY 0.978723 (-3285 5875);
PAINT SKYBLUE (-3285 5875);
DISPLAY INVISIBLE (-3285 5875);
FORCEADD Q_RES..2
(-3525 6050);
FORCEPROP 1 LAST LOCATION R1727
J 0
(-3475 6175);
DISPLAY 0.489362 (-3475 6175);
PAINT SKYBLUE (-3475 6175);
FORCEPROP 2 LAST $SEC 1
J 0
(-3475 6275);
DISPLAY 0.680851 (-3475 6275);
PAINT MONO (-3475 6275);
DISPLAY INVISIBLE (-3475 6275);
FORCEPROP 2 LAST CDS_SEC 1
J 0
(-3475 6275);
DISPLAY 0.680851 (-3475 6275);
DISPLAY INVISIBLE (-3475 6275);
FORCEPROP 1 LASTPIN (-3525 6150) $PN 1
J 0
(-3520 6112);
DISPLAY 0.489362 (-3520 6112);
FORCEPROP 1 LASTPIN (-3525 5950) $PN 2
J 0
(-3520 5960);
DISPLAY 0.489362 (-3520 5960);
FORCEPROP 1 LAST TOLERANCE 1%
J 0
(-3475 6075);
DISPLAY 0.489362 (-3475 6075);
PAINT SKYBLUE (-3475 6075);
FORCEPROP 1 LAST VALUE 10K
J 0
(-3475 6125);
DISPLAY 0.489362 (-3475 6125);
PAINT SKYBLUE (-3475 6125);
FORCEPROP 2 LAST CDS_LIB pure_quanta
J 0
(-3525 6050);
DISPLAY INVISIBLE (-3525 6050);
FORCEPROP 1 LAST PATH I250
J 0
(-3475 6225);
DISPLAY 0.978723 (-3475 6225);
PAINT WHITE (-3475 6225);
DISPLAY INVISIBLE (-3475 6225);
FORCEPROP 1 LAST WATTAGE 1/16W
J 0
(-3485 6025);
DISPLAY 0.978723 (-3485 6025);
PAINT SKYBLUE (-3485 6025);
DISPLAY INVISIBLE (-3485 6025);
FORCEPROP 1 LAST MATERIAL CHIP
J 0
(-3485 5975);
DISPLAY 0.978723 (-3485 5975);
PAINT SKYBLUE (-3485 5975);
DISPLAY INVISIBLE (-3485 5975);
FORCEPROP 1 LAST PART_NUMBER CS31002FB08
J 0
(-3485 5925);
DISPLAY 0.978723 (-3485 5925);
PAINT SKYBLUE (-3485 5925);
DISPLAY INVISIBLE (-3485 5925);
FORCEPROP 1 LAST PACK_TYPE 0402LF
J 0
(-3485 5875);
DISPLAY 0.978723 (-3485 5875);
PAINT SKYBLUE (-3485 5875);
DISPLAY INVISIBLE (-3485 5875);
FORCEADD OFFPAGE..2
R 2
(-4175 5850);
FORCEPROP 2 LAST $XR1 148 
J 0
(-4550 5850);
DISPLAY 0.638298 (-4550 5850);
PAINT MONO (-4550 5850);
FORCEPROP 2 LAST $XR0 117 
J 0
(-4430 5850);
DISPLAY 0.638298 (-4430 5850);
PAINT MONO (-4430 5850);
FORCEPROP 2 LAST CDS_LIB standard
J 0
(-4175 5850);
DISPLAY INVISIBLE (-4175 5850);
FORCEPROP 1 LAST OFFPAGE TRUE
J 2
(-4500 5725);
DISPLAY 0.872340 (-4500 5725);
PAINT GREEN (-4500 5725);
DISPLAY INVISIBLE (-4500 5725);
FORCEPROP 1 LAST COMMENT_BODY TRUE
J 2
(-4130 5755);
DISPLAY 0.872340 (-4130 5755);
PAINT GREEN (-4130 5755);
DISPLAY INVISIBLE (-4130 5755);
FORCEPROP 2 LAST PATH I251
J 0
(-4450 5900);
DISPLAY 1.021277 (-4450 5900);
DISPLAY INVISIBLE (-4450 5900);
FORCEADD OFFPAGE..2
R 2
(-4175 5800);
FORCEPROP 2 LAST $XR1 117 
J 0
(-4550 5800);
DISPLAY 0.638298 (-4550 5800);
PAINT MONO (-4550 5800);
FORCEPROP 2 LAST $XR0 148 
J 0
(-4430 5800);
DISPLAY 0.638298 (-4430 5800);
PAINT MONO (-4430 5800);
FORCEPROP 2 LAST CDS_LIB standard
J 0
(-4175 5800);
DISPLAY INVISIBLE (-4175 5800);
FORCEPROP 1 LAST OFFPAGE TRUE
J 2
(-4500 5675);
DISPLAY 0.872340 (-4500 5675);
PAINT GREEN (-4500 5675);
DISPLAY INVISIBLE (-4500 5675);
FORCEPROP 1 LAST COMMENT_BODY TRUE
J 2
(-4130 5705);
DISPLAY 0.872340 (-4130 5705);
PAINT GREEN (-4130 5705);
DISPLAY INVISIBLE (-4130 5705);
FORCEPROP 2 LAST PATH I252
J 0
(-4450 5850);
DISPLAY 1.021277 (-4450 5850);
DISPLAY INVISIBLE (-4450 5850);
FORCEADD OFFPAGE..2
R 2
(-4175 5750);
FORCEPROP 2 LAST $XR1 148 
J 0
(-4550 5750);
DISPLAY 0.638298 (-4550 5750);
PAINT MONO (-4550 5750);
FORCEPROP 2 LAST $XR0 117 
J 0
(-4430 5750);
DISPLAY 0.638298 (-4430 5750);
PAINT MONO (-4430 5750);
FORCEPROP 2 LAST CDS_LIB standard
J 0
(-4175 5750);
DISPLAY INVISIBLE (-4175 5750);
FORCEPROP 1 LAST OFFPAGE TRUE
J 2
(-4500 5625);
DISPLAY 0.872340 (-4500 5625);
PAINT GREEN (-4500 5625);
DISPLAY INVISIBLE (-4500 5625);
FORCEPROP 1 LAST COMMENT_BODY TRUE
J 2
(-4130 5655);
DISPLAY 0.872340 (-4130 5655);
PAINT GREEN (-4130 5655);
DISPLAY INVISIBLE (-4130 5655);
FORCEPROP 2 LAST PATH I253
J 0
(-4450 5800);
DISPLAY 1.021277 (-4450 5800);
DISPLAY INVISIBLE (-4450 5800);
FORCEADD OFFPAGE..2
R 2
(-4175 5700);
FORCEPROP 2 LAST $XR1 148 
J 0
(-4550 5700);
DISPLAY 0.638298 (-4550 5700);
PAINT MONO (-4550 5700);
FORCEPROP 2 LAST $XR0 117 
J 0
(-4430 5700);
DISPLAY 0.638298 (-4430 5700);
PAINT MONO (-4430 5700);
FORCEPROP 2 LAST CDS_LIB standard
J 0
(-4175 5700);
DISPLAY INVISIBLE (-4175 5700);
FORCEPROP 1 LAST OFFPAGE TRUE
J 2
(-4500 5575);
DISPLAY 0.872340 (-4500 5575);
PAINT GREEN (-4500 5575);
DISPLAY INVISIBLE (-4500 5575);
FORCEPROP 1 LAST COMMENT_BODY TRUE
J 2
(-4130 5605);
DISPLAY 0.872340 (-4130 5605);
PAINT GREEN (-4130 5605);
DISPLAY INVISIBLE (-4130 5605);
FORCEPROP 2 LAST PATH I254
J 0
(-4450 5750);
DISPLAY 1.021277 (-4450 5750);
DISPLAY INVISIBLE (-4450 5750);
FORCEADD Q_RES..2
(-450 6025);
FORCEPROP 1 LAST LOCATION R1747
J 0
(-405 6150);
DISPLAY 0.489362 (-405 6150);
PAINT SKYBLUE (-405 6150);
FORCEPROP 0 LAST $SEC 1
J 0
(-400 6200);
PAINT MONO (-400 6200);
DISPLAY INVISIBLE (-400 6200);
FORCEPROP 0 LAST CDS_SEC 1
J 0
(-400 6200);
PAINT MONO (-400 6200);
DISPLAY INVISIBLE (-400 6200);
FORCEPROP 1 LASTPIN (-450 6125) $PN 1
J 0
(-445 6087);
DISPLAY 0.489362 (-445 6087);
PAINT GREEN (-445 6087);
FORCEPROP 1 LASTPIN (-450 5925) $PN 2
J 0
(-445 5935);
DISPLAY 0.489362 (-445 5935);
PAINT GREEN (-445 5935);
FORCEPROP 1 LAST WATTAGE 1/16W
J 0
(-410 6000);
DISPLAY 0.489362 (-410 6000);
PAINT SKYBLUE (-410 6000);
FORCEPROP 1 LAST MATERIAL CHIP
J 0
(-410 5950);
DISPLAY 0.489362 (-410 5950);
PAINT SKYBLUE (-410 5950);
FORCEPROP 1 LAST TOLERANCE 1%
J 0
(-405 6050);
DISPLAY 0.489362 (-405 6050);
PAINT SKYBLUE (-405 6050);
FORCEPROP 1 LAST VALUE 10K
J 0
(-405 6100);
DISPLAY 0.489362 (-405 6100);
PAINT SKYBLUE (-405 6100);
FORCEPROP 1 LAST PART_NUMBER CS31002FB08
J 0
(-410 5900);
DISPLAY 0.489362 (-410 5900);
PAINT SKYBLUE (-410 5900);
FORCEPROP 1 LAST PACK_TYPE 0402LF
J 0
(-410 5850);
DISPLAY 0.489362 (-410 5850);
PAINT SKYBLUE (-410 5850);
FORCEPROP 2 LAST CDS_LIB pure_quanta
J 0
(-450 6025);
PAINT MONO (-450 6025);
DISPLAY INVISIBLE (-450 6025);
FORCEPROP 1 LAST PATH I255
J 0
(-400 6200);
DISPLAY 0.978723 (-400 6200);
PAINT WHITE (-400 6200);
DISPLAY INVISIBLE (-400 6200);
FORCEADD Q_RES..2
(-675 6025);
FORCEPROP 1 LAST LOCATION R1746
J 0
(-630 6150);
DISPLAY 0.489362 (-630 6150);
PAINT SKYBLUE (-630 6150);
FORCEPROP 2 LAST $SEC 1
J 0
(-625 6250);
DISPLAY 0.680851 (-625 6250);
PAINT MONO (-625 6250);
DISPLAY INVISIBLE (-625 6250);
FORCEPROP 2 LAST CDS_SEC 1
J 0
(-625 6250);
DISPLAY 0.680851 (-625 6250);
DISPLAY INVISIBLE (-625 6250);
FORCEPROP 1 LASTPIN (-675 6125) $PN 1
J 0
(-670 6087);
DISPLAY 0.489362 (-670 6087);
FORCEPROP 1 LASTPIN (-675 5925) $PN 2
J 0
(-670 5935);
DISPLAY 0.489362 (-670 5935);
FORCEPROP 1 LAST WATTAGE 1/16W
J 0
(-635 6000);
DISPLAY 0.489362 (-635 6000);
PAINT SKYBLUE (-635 6000);
FORCEPROP 1 LAST MATERIAL CHIP
J 0
(-635 5950);
DISPLAY 0.489362 (-635 5950);
PAINT SKYBLUE (-635 5950);
FORCEPROP 1 LAST TOLERANCE 1%
J 0
(-630 6050);
DISPLAY 0.489362 (-630 6050);
PAINT SKYBLUE (-630 6050);
FORCEPROP 1 LAST VALUE 10K
J 0
(-630 6100);
DISPLAY 0.489362 (-630 6100);
PAINT SKYBLUE (-630 6100);
FORCEPROP 1 LAST PACK_TYPE 0402LF
J 0
(-625 5900);
DISPLAY 0.489362 (-625 5900);
PAINT SKYBLUE (-625 5900);
FORCEPROP 2 LAST CDS_LIB pure_quanta
J 0
(-675 6025);
DISPLAY INVISIBLE (-675 6025);
FORCEPROP 1 LAST PATH I256
J 0
(-625 6200);
DISPLAY 0.978723 (-625 6200);
PAINT WHITE (-625 6200);
DISPLAY INVISIBLE (-625 6200);
FORCEPROP 1 LAST PART_NUMBER CS31002FB08
J 0
(-635 5900);
DISPLAY 0.617021 (-635 5900);
PAINT SKYBLUE (-635 5900);
DISPLAY INVISIBLE (-635 5900);
FORCEADD Q_RES..2
(-875 6025);
FORCEPROP 1 LAST LOCATION R1745
J 0
(-825 6150);
DISPLAY 0.489362 (-825 6150);
PAINT SKYBLUE (-825 6150);
FORCEPROP 2 LAST $SEC 1
J 0
(-825 6250);
DISPLAY 0.680851 (-825 6250);
PAINT MONO (-825 6250);
DISPLAY INVISIBLE (-825 6250);
FORCEPROP 2 LAST CDS_SEC 1
J 0
(-825 6250);
DISPLAY 0.680851 (-825 6250);
DISPLAY INVISIBLE (-825 6250);
FORCEPROP 1 LASTPIN (-875 6125) $PN 1
J 0
(-870 6087);
DISPLAY 0.489362 (-870 6087);
FORCEPROP 1 LASTPIN (-875 5925) $PN 2
J 0
(-870 5935);
DISPLAY 0.489362 (-870 5935);
FORCEPROP 1 LAST TOLERANCE 1%
J 0
(-825 6050);
DISPLAY 0.489362 (-825 6050);
PAINT SKYBLUE (-825 6050);
FORCEPROP 1 LAST VALUE 10K
J 0
(-825 6100);
DISPLAY 0.489362 (-825 6100);
PAINT SKYBLUE (-825 6100);
FORCEPROP 2 LAST CDS_LIB pure_quanta
J 0
(-875 6025);
DISPLAY INVISIBLE (-875 6025);
FORCEPROP 1 LAST PATH I257
J 0
(-825 6200);
DISPLAY 0.978723 (-825 6200);
PAINT WHITE (-825 6200);
DISPLAY INVISIBLE (-825 6200);
FORCEPROP 1 LAST WATTAGE 1/16W
J 0
(-835 6000);
DISPLAY 0.978723 (-835 6000);
PAINT SKYBLUE (-835 6000);
DISPLAY INVISIBLE (-835 6000);
FORCEPROP 1 LAST MATERIAL CHIP
J 0
(-835 5950);
DISPLAY 0.978723 (-835 5950);
PAINT SKYBLUE (-835 5950);
DISPLAY INVISIBLE (-835 5950);
FORCEPROP 1 LAST PART_NUMBER CS31002FB08
J 0
(-835 5900);
DISPLAY 0.978723 (-835 5900);
PAINT SKYBLUE (-835 5900);
DISPLAY INVISIBLE (-835 5900);
FORCEPROP 1 LAST PACK_TYPE 0402LF
J 0
(-835 5850);
DISPLAY 0.978723 (-835 5850);
PAINT SKYBLUE (-835 5850);
DISPLAY INVISIBLE (-835 5850);
FORCEADD Q_RES..2
(-450 5525);
FORCEPROP 1 LAST LOCATION R1748
J 0
(-400 5550);
DISPLAY 0.489362 (-400 5550);
PAINT SKYBLUE (-400 5550);
FORCEPROP 2 LAST $SEC 1
J 0
(-400 5750);
DISPLAY 0.680851 (-400 5750);
PAINT MONO (-400 5750);
DISPLAY INVISIBLE (-400 5750);
FORCEPROP 2 LAST CDS_SEC 1
J 0
(-400 5750);
DISPLAY 0.680851 (-400 5750);
DISPLAY INVISIBLE (-400 5750);
FORCEPROP 1 LASTPIN (-450 5625) $PN 1
J 0
(-445 5587);
DISPLAY 0.489362 (-445 5587);
FORCEPROP 1 LASTPIN (-450 5425) $PN 2
J 0
(-445 5435);
DISPLAY 0.489362 (-445 5435);
FORCEPROP 1 LAST MATERIAL EMPTY
J 0
(-400 5400);
DISPLAY 0.489362 (-400 5400);
PAINT RED (-400 5400);
FORCEPROP 1 LAST TOLERANCE 1%
J 0
(-400 5450);
DISPLAY 0.489362 (-400 5450);
PAINT SKYBLUE (-400 5450);
FORCEPROP 1 LAST VALUE 10K
J 0
(-400 5500);
DISPLAY 0.489362 (-400 5500);
PAINT SKYBLUE (-400 5500);
FORCEPROP 2 LAST CDS_LIB pure_quanta
J 0
(-450 5525);
DISPLAY INVISIBLE (-450 5525);
FORCEPROP 1 LAST PATH I258
J 0
(-400 5700);
DISPLAY 0.978723 (-400 5700);
PAINT WHITE (-400 5700);
DISPLAY INVISIBLE (-400 5700);
FORCEPROP 1 LAST WATTAGE 1/16W
J 0
(-410 5500);
DISPLAY 0.978723 (-410 5500);
PAINT SKYBLUE (-410 5500);
DISPLAY INVISIBLE (-410 5500);
FORCEPROP 1 LAST PART_NUMBER CS31002FB08
J 0
(-410 5400);
DISPLAY 0.978723 (-410 5400);
PAINT SKYBLUE (-410 5400);
DISPLAY INVISIBLE (-410 5400);
FORCEPROP 1 LAST PACK_TYPE 0402LF
J 0
(-410 5350);
DISPLAY 0.978723 (-410 5350);
PAINT SKYBLUE (-410 5350);
DISPLAY INVISIBLE (-410 5350);
FORCEADD UNIVERSAL_GND..1
(-450 5300);
FORCEPROP 3 LASTPIN (-450 5350) SIG_NAME GND\g
J 0
(-440 5360);
DISPLAY 0.659574 (-440 5360);
PAINT MONO (-440 5360);
DISPLAY INVISIBLE (-440 5360);
FORCEPROP 2 LAST CDS_LIB pure_quanta_power
J 0
(-450 5300);
DISPLAY INVISIBLE (-450 5300);
FORCEPROP 1 LAST PATH I259
J 0
(-375 5300);
DISPLAY 0.872340 (-375 5300);
PAINT AQUA (-375 5300);
DISPLAY INVISIBLE (-375 5300);
FORCEPROP 1 LAST HDL_POWER GND
J 1
(-425 5225);
DISPLAY 0.872340 (-425 5225);
PAINT GREEN (-425 5225);
DISPLAY INVISIBLE (-425 5225);
FORCEADD UNIVERSAL_POWER..1
(-1075 6375);
FORCEPROP 3 LASTPIN (-1075 6325) SIG_NAME P3V3_STBY\g
J 0
(-1065 6335);
DISPLAY 0.659574 (-1065 6335);
PAINT MONO (-1065 6335);
DISPLAY INVISIBLE (-1065 6335);
FORCEPROP 1 LAST HDL_POWER P3V3_STBY
J 1
(-1075 6425);
DISPLAY 0.489362 (-1075 6425);
PAINT GREEN (-1075 6425);
FORCEPROP 2 LAST CDS_LIB pure_quanta_power
J 0
(-1075 6375);
DISPLAY INVISIBLE (-1075 6375);
FORCEPROP 1 LAST PATH I260
J 0
(-1025 6400);
DISPLAY 0.872340 (-1025 6400);
PAINT AQUA (-1025 6400);
DISPLAY INVISIBLE (-1025 6400);
FORCEADD Q_RES..2
(-1075 6025);
FORCEPROP 1 LAST LOCATION R1744
J 0
(-1025 6150);
DISPLAY 0.489362 (-1025 6150);
PAINT SKYBLUE (-1025 6150);
FORCEPROP 2 LAST $SEC 1
J 0
(-1025 6250);
DISPLAY 0.680851 (-1025 6250);
PAINT MONO (-1025 6250);
DISPLAY INVISIBLE (-1025 6250);
FORCEPROP 2 LAST CDS_SEC 1
J 0
(-1025 6250);
DISPLAY 0.680851 (-1025 6250);
DISPLAY INVISIBLE (-1025 6250);
FORCEPROP 1 LASTPIN (-1075 6125) $PN 1
J 0
(-1070 6087);
DISPLAY 0.489362 (-1070 6087);
FORCEPROP 1 LASTPIN (-1075 5925) $PN 2
J 0
(-1070 5935);
DISPLAY 0.489362 (-1070 5935);
FORCEPROP 1 LAST TOLERANCE 1%
J 0
(-1025 6050);
DISPLAY 0.489362 (-1025 6050);
PAINT SKYBLUE (-1025 6050);
FORCEPROP 1 LAST VALUE 10K
J 0
(-1025 6100);
DISPLAY 0.489362 (-1025 6100);
PAINT SKYBLUE (-1025 6100);
FORCEPROP 2 LAST CDS_LIB pure_quanta
J 0
(-1075 6025);
DISPLAY INVISIBLE (-1075 6025);
FORCEPROP 1 LAST PATH I261
J 0
(-1025 6200);
DISPLAY 0.978723 (-1025 6200);
PAINT WHITE (-1025 6200);
DISPLAY INVISIBLE (-1025 6200);
FORCEPROP 1 LAST WATTAGE 1/16W
J 0
(-1035 6000);
DISPLAY 0.978723 (-1035 6000);
PAINT SKYBLUE (-1035 6000);
DISPLAY INVISIBLE (-1035 6000);
FORCEPROP 1 LAST MATERIAL CHIP
J 0
(-1035 5950);
DISPLAY 0.978723 (-1035 5950);
PAINT SKYBLUE (-1035 5950);
DISPLAY INVISIBLE (-1035 5950);
FORCEPROP 1 LAST PART_NUMBER CS31002FB08
J 0
(-1035 5900);
DISPLAY 0.978723 (-1035 5900);
PAINT SKYBLUE (-1035 5900);
DISPLAY INVISIBLE (-1035 5900);
FORCEPROP 1 LAST PACK_TYPE 0402LF
J 0
(-1035 5850);
DISPLAY 0.978723 (-1035 5850);
PAINT SKYBLUE (-1035 5850);
DISPLAY INVISIBLE (-1035 5850);
FORCEADD OFFPAGE..2
R 2
(-2000 5825);
FORCEPROP 2 LAST $XR1 148 
J 0
(-2405 5825);
DISPLAY 0.638298 (-2405 5825);
PAINT MONO (-2405 5825);
FORCEPROP 2 LAST $XR0 149 
J 0
(-2285 5825);
DISPLAY 0.638298 (-2285 5825);
PAINT MONO (-2285 5825);
FORCEPROP 2 LAST CDS_LIB standard
J 0
(-2000 5825);
DISPLAY INVISIBLE (-2000 5825);
FORCEPROP 1 LAST OFFPAGE TRUE
J 2
(-2325 5700);
DISPLAY 0.872340 (-2325 5700);
PAINT GREEN (-2325 5700);
DISPLAY INVISIBLE (-2325 5700);
FORCEPROP 1 LAST COMMENT_BODY TRUE
J 2
(-1955 5730);
DISPLAY 0.872340 (-1955 5730);
PAINT GREEN (-1955 5730);
DISPLAY INVISIBLE (-1955 5730);
FORCEPROP 2 LAST PATH I262
J 0
(-2250 5875);
DISPLAY 1.021277 (-2250 5875);
DISPLAY INVISIBLE (-2250 5875);
FORCEADD OFFPAGE..2
R 2
(-2000 5775);
FORCEPROP 2 LAST $XR1 149 
J 0
(-2405 5775);
DISPLAY 0.638298 (-2405 5775);
PAINT MONO (-2405 5775);
FORCEPROP 2 LAST $XR0 148 
J 0
(-2285 5775);
DISPLAY 0.638298 (-2285 5775);
PAINT MONO (-2285 5775);
FORCEPROP 2 LAST CDS_LIB standard
J 0
(-2000 5775);
DISPLAY INVISIBLE (-2000 5775);
FORCEPROP 1 LAST OFFPAGE TRUE
J 2
(-2325 5650);
DISPLAY 0.872340 (-2325 5650);
PAINT GREEN (-2325 5650);
DISPLAY INVISIBLE (-2325 5650);
FORCEPROP 1 LAST COMMENT_BODY TRUE
J 2
(-1955 5680);
DISPLAY 0.872340 (-1955 5680);
PAINT GREEN (-1955 5680);
DISPLAY INVISIBLE (-1955 5680);
FORCEPROP 2 LAST PATH I263
J 0
(-2250 5825);
DISPLAY 1.021277 (-2250 5825);
DISPLAY INVISIBLE (-2250 5825);
FORCEADD OFFPAGE..2
R 2
(-2000 5725);
FORCEPROP 2 LAST $XR1 149 
J 0
(-2405 5725);
DISPLAY 0.638298 (-2405 5725);
PAINT MONO (-2405 5725);
FORCEPROP 2 LAST $XR0 148 
J 0
(-2285 5725);
DISPLAY 0.638298 (-2285 5725);
PAINT MONO (-2285 5725);
FORCEPROP 2 LAST CDS_LIB standard
J 0
(-2000 5725);
DISPLAY INVISIBLE (-2000 5725);
FORCEPROP 1 LAST OFFPAGE TRUE
J 2
(-2325 5600);
DISPLAY 0.872340 (-2325 5600);
PAINT GREEN (-2325 5600);
DISPLAY INVISIBLE (-2325 5600);
FORCEPROP 1 LAST COMMENT_BODY TRUE
J 2
(-1955 5630);
DISPLAY 0.872340 (-1955 5630);
PAINT GREEN (-1955 5630);
DISPLAY INVISIBLE (-1955 5630);
FORCEPROP 2 LAST PATH I264
J 0
(-2250 5775);
DISPLAY 1.021277 (-2250 5775);
DISPLAY INVISIBLE (-2250 5775);
FORCEADD OFFPAGE..2
R 2
(-2000 5675);
FORCEPROP 2 LAST $XR1 149 
J 0
(-2405 5675);
DISPLAY 0.638298 (-2405 5675);
PAINT MONO (-2405 5675);
FORCEPROP 2 LAST $XR0 148 
J 0
(-2285 5675);
DISPLAY 0.638298 (-2285 5675);
PAINT MONO (-2285 5675);
FORCEPROP 2 LAST CDS_LIB standard
J 0
(-2000 5675);
DISPLAY INVISIBLE (-2000 5675);
FORCEPROP 1 LAST OFFPAGE TRUE
J 2
(-2325 5550);
DISPLAY 0.872340 (-2325 5550);
PAINT GREEN (-2325 5550);
DISPLAY INVISIBLE (-2325 5550);
FORCEPROP 1 LAST COMMENT_BODY TRUE
J 2
(-1955 5580);
DISPLAY 0.872340 (-1955 5580);
PAINT GREEN (-1955 5580);
DISPLAY INVISIBLE (-1955 5580);
FORCEPROP 2 LAST PATH I265
J 0
(-2250 5725);
DISPLAY 1.021277 (-2250 5725);
DISPLAY INVISIBLE (-2250 5725);
FORCEADD 74HC4052PW..1
(-4875 4050);
FORCEPROP 1 LAST LOCATION U160
J 0
(-5052 4657);
DISPLAY 0.489362 (-5052 4657);
PAINT SKYBLUE (-5052 4657);
FORCEPROP 0 LAST $SEC 1
J 0
(-5050 4800);
DISPLAY 0.680851 (-5050 4800);
PAINT MONO (-5050 4800);
DISPLAY INVISIBLE (-5050 4800);
FORCEPROP 0 LAST CDS_SEC 1
J 0
(-5050 4800);
DISPLAY 1.021277 (-5050 4800);
DISPLAY INVISIBLE (-5050 4800);
FORCEPROP 0 LASTPIN (-4550 4175) $PN 12
J 0
(-4540 4185);
DISPLAY 0.489362 (-4540 4185);
PAINT MONO (-4540 4185);
FORCEPROP 0 LASTPIN (-4550 4225) $PN 14
J 0
(-4540 4235);
DISPLAY 0.489362 (-4540 4235);
PAINT MONO (-4540 4235);
FORCEPROP 0 LASTPIN (-4550 4275) $PN 15
J 0
(-4540 4285);
DISPLAY 0.489362 (-4540 4285);
PAINT MONO (-4540 4285);
FORCEPROP 0 LASTPIN (-4550 4325) $PN 11
J 0
(-4540 4335);
DISPLAY 0.489362 (-4540 4335);
PAINT MONO (-4540 4335);
FORCEPROP 0 LASTPIN (-5200 4275) $PN 13
J 2
(-5210 4285);
DISPLAY 0.489362 (-5210 4285);
PAINT MONO (-5210 4285);
FORCEPROP 0 LASTPIN (-4550 3925) $PN 1
J 0
(-4540 3935);
DISPLAY 0.489362 (-4540 3935);
PAINT MONO (-4540 3935);
FORCEPROP 0 LASTPIN (-4550 3975) $PN 5
J 0
(-4540 3985);
DISPLAY 0.489362 (-4540 3985);
PAINT MONO (-4540 3985);
FORCEPROP 0 LASTPIN (-4550 4025) $PN 2
J 0
(-4540 4035);
DISPLAY 0.489362 (-4540 4035);
PAINT MONO (-4540 4035);
FORCEPROP 0 LASTPIN (-4550 4075) $PN 4
J 0
(-4540 4085);
DISPLAY 0.489362 (-4540 4085);
PAINT MONO (-4540 4085);
FORCEPROP 0 LASTPIN (-5200 4075) $PN 3
J 2
(-5210 4085);
DISPLAY 0.489362 (-5210 4085);
PAINT MONO (-5210 4085);
FORCEPROP 0 LASTPIN (-5200 3825) $PN 6
J 2
(-5210 3835);
DISPLAY 0.489362 (-5210 3835);
PAINT MONO (-5210 3835);
FORCEPROP 0 LASTPIN (-4550 3775) $PN 8
J 0
(-4540 3785);
DISPLAY 0.489362 (-4540 3785);
PAINT MONO (-4540 3785);
FORCEPROP 0 LASTPIN (-5200 3875) $PN 10
J 2
(-5210 3885);
DISPLAY 0.489362 (-5210 3885);
PAINT MONO (-5210 3885);
FORCEPROP 0 LASTPIN (-5200 3925) $PN 9
J 2
(-5210 3935);
DISPLAY 0.489362 (-5210 3935);
PAINT MONO (-5210 3935);
FORCEPROP 0 LASTPIN (-5200 4325) $PN 16
J 2
(-5210 4335);
DISPLAY 0.489362 (-5210 4335);
PAINT MONO (-5210 4335);
FORCEPROP 0 LASTPIN (-4550 3825) $PN 7
J 0
(-4540 3835);
DISPLAY 0.489362 (-4540 3835);
PAINT MONO (-4540 3835);
FORCEPROP 2 LAST PART_TYPE SMLF
J 0
(-5050 4750);
DISPLAY 1.021277 (-5050 4750);
FORCEPROP 1 LAST MATERIAL IC
J 0
(-5052 4383);
DISPLAY 0.489362 (-5052 4383);
PAINT SKYBLUE (-5052 4383);
FORCEPROP 2 LAST VALUE 74HC4052PW
J 0
(-5050 4700);
DISPLAY 0.489362 (-5050 4700);
PAINT SKYBLUE (-5050 4700);
FORCEPROP 1 LAST PART_NUMBER ALHC4052K07
J 0
(-5052 4510);
DISPLAY 0.489362 (-5052 4510);
PAINT SKYBLUE (-5052 4510);
FORCEPROP 1 LAST CDS_LMAN_SYM_OUTLINE -175,325,175,-325
J 0
(-4875 4050);
DISPLAY 0.468085 (-4875 4050);
PAINT GREEN (-4875 4050);
DISPLAY INVISIBLE (-4875 4050);
FORCEPROP 1 LAST NEEDS_NO_SIZE TRUE
J 0
(-4875 4050);
DISPLAY 0.723404 (-4875 4050);
PAINT GREEN (-4875 4050);
DISPLAY INVISIBLE (-4875 4050);
FORCEPROP 2 LAST CDS_LIB pure_quanta
J 0
(-4875 4050);
DISPLAY INVISIBLE (-4875 4050);
FORCEPROP 1 LAST PATH I266
J 0
(-4875 4050);
DISPLAY 0.723404 (-4875 4050);
PAINT GREEN (-4875 4050);
DISPLAY INVISIBLE (-4875 4050);
FORCEADD UNIVERSAL_GND..1
(-4475 3525);
FORCEPROP 3 LASTPIN (-4475 3575) SIG_NAME GND\g
J 0
(-4465 3585);
DISPLAY 0.659574 (-4465 3585);
PAINT MONO (-4465 3585);
DISPLAY INVISIBLE (-4465 3585);
FORCEPROP 2 LAST CDS_LIB pure_quanta_power
J 0
(-4475 3525);
PAINT MONO (-4475 3525);
DISPLAY INVISIBLE (-4475 3525);
FORCEPROP 1 LAST PATH I267
J 0
(-4400 3525);
DISPLAY 0.872340 (-4400 3525);
PAINT AQUA (-4400 3525);
DISPLAY INVISIBLE (-4400 3525);
FORCEPROP 1 LAST HDL_POWER GND
J 1
(-4450 3450);
DISPLAY 0.872340 (-4450 3450);
PAINT GREEN (-4450 3450);
DISPLAY INVISIBLE (-4450 3450);
FORCEADD UNIVERSAL_POWER..1
(-5350 4875);
FORCEPROP 3 LASTPIN (-5350 4825) SIG_NAME P3V3_STBY\g
J 0
(-5340 4835);
DISPLAY 0.659574 (-5340 4835);
PAINT MONO (-5340 4835);
DISPLAY INVISIBLE (-5340 4835);
FORCEPROP 1 LAST HDL_POWER P3V3_STBY
J 1
(-5350 4925);
DISPLAY 0.489362 (-5350 4925);
PAINT GREEN (-5350 4925);
FORCEPROP 2 LAST CDS_LIB pure_quanta_power
J 0
(-5350 4875);
PAINT MONO (-5350 4875);
DISPLAY INVISIBLE (-5350 4875);
FORCEPROP 1 LAST PATH I292
J 0
(-5300 4900);
DISPLAY 0.872340 (-5300 4900);
PAINT AQUA (-5300 4900);
DISPLAY INVISIBLE (-5300 4900);
FORCEADD Q_CAP..1
(-5475 4575);
FORCEPROP 1 LAST LOCATION C1554
J 0
(-5675 4675);
DISPLAY 0.489362 (-5675 4675);
PAINT SKYBLUE (-5675 4675);
FORCEPROP 2 LAST $SEC 1
J 0
(-5425 4775);
PAINT MONO (-5425 4775);
DISPLAY INVISIBLE (-5425 4775);
FORCEPROP 2 LAST CDS_SEC 1
J 0
(-5425 4775);
PAINT MONO (-5425 4775);
DISPLAY INVISIBLE (-5425 4775);
FORCEPROP 1 LASTPIN (-5475 4675) $PN 1
J 0
(-5465 4655);
DISPLAY 0.489362 (-5465 4655);
PAINT GREEN (-5465 4655);
FORCEPROP 1 LASTPIN (-5475 4475) $PN 2
J 0
(-5465 4455);
DISPLAY 0.489362 (-5465 4455);
PAINT GREEN (-5465 4455);
FORCEPROP 1 LAST MATERIAL X7R
J 0
(-5650 4375);
DISPLAY 0.489362 (-5650 4375);
PAINT SKYBLUE (-5650 4375);
FORCEPROP 1 LAST TOLERANCE 10%
J 0
(-5650 4525);
DISPLAY 0.489362 (-5650 4525);
PAINT SKYBLUE (-5650 4525);
FORCEPROP 1 LAST VALUE 0.1UF
J 0
(-5700 4625);
DISPLAY 0.489362 (-5700 4625);
PAINT SKYBLUE (-5700 4625);
FORCEPROP 1 LAST PART_NUMBER CH4103K1B08
J 0
(-5825 4475);
DISPLAY 0.489362 (-5825 4475);
PAINT SKYBLUE (-5825 4475);
FORCEPROP 1 LAST VOLTAGE 16V
J 0
(-5650 4575);
DISPLAY 0.489362 (-5650 4575);
PAINT SKYBLUE (-5650 4575);
FORCEPROP 1 LAST PACK_TYPE C0402
J 0
(-5700 4425);
DISPLAY 0.489362 (-5700 4425);
PAINT SKYBLUE (-5700 4425);
FORCEPROP 2 LAST CDS_LIB pure_quanta
J 0
(-5475 4575);
DISPLAY INVISIBLE (-5475 4575);
FORCEPROP 1 LAST PATH I293
J 0
(-5425 4725);
DISPLAY 0.978723 (-5425 4725);
PAINT WHITE (-5425 4725);
DISPLAY INVISIBLE (-5425 4725);
FORCEADD UNIVERSAL_GND..1
(-5475 4375);
FORCEPROP 3 LASTPIN (-5475 4425) SIG_NAME GND\g
J 0
(-5465 4435);
DISPLAY 0.659574 (-5465 4435);
PAINT MONO (-5465 4435);
DISPLAY INVISIBLE (-5465 4435);
FORCEPROP 2 LAST CDS_LIB pure_quanta_power
J 0
(-5475 4375);
PAINT MONO (-5475 4375);
DISPLAY INVISIBLE (-5475 4375);
FORCEPROP 1 LAST PATH I294
J 0
(-5400 4375);
DISPLAY 0.872340 (-5400 4375);
PAINT AQUA (-5400 4375);
DISPLAY INVISIBLE (-5400 4375);
FORCEPROP 1 LAST HDL_POWER GND
J 1
(-5450 4300);
DISPLAY 0.872340 (-5450 4300);
PAINT GREEN (-5450 4300);
DISPLAY INVISIBLE (-5450 4300);
FORCEADD UNIVERSAL_POWER..1
(-7700 4375);
FORCEPROP 3 LASTPIN (-7700 4325) SIG_NAME P3V3_STBY\g
J 0
(-7690 4335);
DISPLAY 0.659574 (-7690 4335);
PAINT MONO (-7690 4335);
DISPLAY INVISIBLE (-7690 4335);
FORCEPROP 1 LAST HDL_POWER P3V3_STBY
J 1
(-7700 4425);
DISPLAY 0.489362 (-7700 4425);
PAINT GREEN (-7700 4425);
FORCEPROP 2 LAST CDS_LIB pure_quanta_power
J 0
(-7700 4375);
DISPLAY INVISIBLE (-7700 4375);
FORCEPROP 1 LAST PATH I295
J 0
(-7650 4400);
DISPLAY 0.872340 (-7650 4400);
PAINT AQUA (-7650 4400);
DISPLAY INVISIBLE (-7650 4400);
FORCEADD OFFPAGE..4
R 2
(-5900 4275);
FORCEPROP 2 LAST $XR1 148 
J 0
(-6302 4275);
DISPLAY 0.638298 (-6302 4275);
PAINT MONO (-6302 4275);
FORCEPROP 2 LAST $XR0 117 
J 0
(-6182 4275);
DISPLAY 0.638298 (-6182 4275);
PAINT MONO (-6182 4275);
FORCEPROP 2 LAST CDS_LIB standard
J 0
(-5900 4275);
DISPLAY INVISIBLE (-5900 4275);
FORCEPROP 1 LAST OFFPAGE TRUE
J 2
(-6225 4150);
DISPLAY 0.872340 (-6225 4150);
PAINT GREEN (-6225 4150);
DISPLAY INVISIBLE (-6225 4150);
FORCEPROP 1 LAST COMMENT_BODY TRUE
J 2
(-5875 4175);
DISPLAY 0.872340 (-5875 4175);
PAINT GREEN (-5875 4175);
DISPLAY INVISIBLE (-5875 4175);
FORCEPROP 2 LAST PATH I296
J 0
(-6150 4325);
DISPLAY 1.021277 (-6150 4325);
DISPLAY INVISIBLE (-6150 4325);
FORCEADD OFFPAGE..4
R 2
(-5900 4075);
FORCEPROP 2 LAST $XR1 148 
J 0
(-6302 4075);
DISPLAY 0.638298 (-6302 4075);
PAINT MONO (-6302 4075);
FORCEPROP 2 LAST $XR0 117 
J 0
(-6182 4075);
DISPLAY 0.638298 (-6182 4075);
PAINT MONO (-6182 4075);
FORCEPROP 2 LAST CDS_LIB standard
J 0
(-5900 4075);
DISPLAY INVISIBLE (-5900 4075);
FORCEPROP 1 LAST OFFPAGE TRUE
J 2
(-6225 3950);
DISPLAY 0.872340 (-6225 3950);
PAINT GREEN (-6225 3950);
DISPLAY INVISIBLE (-6225 3950);
FORCEPROP 1 LAST COMMENT_BODY TRUE
J 2
(-5875 3975);
DISPLAY 0.872340 (-5875 3975);
PAINT GREEN (-5875 3975);
DISPLAY INVISIBLE (-5875 3975);
FORCEPROP 2 LAST PATH I297
J 0
(-6150 4125);
DISPLAY 1.021277 (-6150 4125);
DISPLAY INVISIBLE (-6150 4125);
FORCEADD UNIVERSAL_POWER..1
(-5350 2925);
FORCEPROP 3 LASTPIN (-5350 2875) SIG_NAME P3V3_STBY\g
J 0
(-5340 2885);
DISPLAY 0.659574 (-5340 2885);
PAINT MONO (-5340 2885);
DISPLAY INVISIBLE (-5340 2885);
FORCEPROP 1 LAST HDL_POWER P3V3_STBY
J 1
(-5350 2975);
DISPLAY 0.489362 (-5350 2975);
PAINT GREEN (-5350 2975);
FORCEPROP 2 LAST CDS_LIB pure_quanta_power
J 0
(-5350 2925);
DISPLAY INVISIBLE (-5350 2925);
FORCEPROP 1 LAST PATH I298
J 0
(-5300 2950);
DISPLAY 0.872340 (-5300 2950);
PAINT AQUA (-5300 2950);
DISPLAY INVISIBLE (-5300 2950);
FORCEADD Q_CAP..1
(-5475 2625);
FORCEPROP 1 LAST LOCATION C194
J 0
(-5625 2725);
DISPLAY 0.489362 (-5625 2725);
PAINT SKYBLUE (-5625 2725);
FORCEPROP 0 LAST $SEC 1
J 0
(-5625 2775);
DISPLAY 0.680851 (-5625 2775);
PAINT MONO (-5625 2775);
DISPLAY INVISIBLE (-5625 2775);
FORCEPROP 0 LAST CDS_SEC 1
J 0
(-5625 2775);
DISPLAY 1.021277 (-5625 2775);
DISPLAY INVISIBLE (-5625 2775);
FORCEPROP 1 LASTPIN (-5475 2725) $PN 1
J 0
(-5465 2705);
DISPLAY 0.489362 (-5465 2705);
PAINT MONO (-5465 2705);
FORCEPROP 1 LASTPIN (-5475 2525) $PN 2
J 0
(-5465 2505);
DISPLAY 0.489362 (-5465 2505);
PAINT MONO (-5465 2505);
FORCEPROP 1 LAST MATERIAL X7R
J 0
(-5650 2425);
DISPLAY 0.489362 (-5650 2425);
PAINT SKYBLUE (-5650 2425);
FORCEPROP 1 LAST TOLERANCE 10%
J 0
(-5650 2575);
DISPLAY 0.489362 (-5650 2575);
PAINT SKYBLUE (-5650 2575);
FORCEPROP 1 LAST VALUE 0.1UF
J 0
(-5700 2675);
DISPLAY 0.489362 (-5700 2675);
PAINT SKYBLUE (-5700 2675);
FORCEPROP 1 LAST PART_NUMBER CH4103K1B08
J 0
(-5825 2525);
DISPLAY 0.489362 (-5825 2525);
PAINT SKYBLUE (-5825 2525);
FORCEPROP 1 LAST VOLTAGE 16V
J 0
(-5650 2625);
DISPLAY 0.489362 (-5650 2625);
PAINT SKYBLUE (-5650 2625);
FORCEPROP 1 LAST PACK_TYPE C0402
J 0
(-5700 2475);
DISPLAY 0.489362 (-5700 2475);
PAINT SKYBLUE (-5700 2475);
FORCEPROP 2 LAST CDS_LIB pure_quanta
J 0
(-5475 2625);
DISPLAY INVISIBLE (-5475 2625);
FORCEPROP 1 LAST PATH I299
J 0
(-5425 2775);
DISPLAY 0.978723 (-5425 2775);
PAINT WHITE (-5425 2775);
DISPLAY INVISIBLE (-5425 2775);
FORCEADD UNIVERSAL_GND..1
(-5475 2425);
FORCEPROP 3 LASTPIN (-5475 2475) SIG_NAME GND\g
J 0
(-5465 2485);
DISPLAY 0.659574 (-5465 2485);
PAINT MONO (-5465 2485);
DISPLAY INVISIBLE (-5465 2485);
FORCEPROP 2 LAST CDS_LIB pure_quanta_power
J 0
(-5475 2425);
DISPLAY INVISIBLE (-5475 2425);
FORCEPROP 1 LAST PATH I300
J 0
(-5400 2425);
DISPLAY 0.872340 (-5400 2425);
PAINT AQUA (-5400 2425);
DISPLAY INVISIBLE (-5400 2425);
FORCEPROP 1 LAST HDL_POWER GND
J 1
(-5450 2350);
DISPLAY 0.872340 (-5450 2350);
PAINT GREEN (-5450 2350);
DISPLAY INVISIBLE (-5450 2350);
FORCEADD UNIVERSAL_GND..1
(-4425 1600);
FORCEPROP 3 LASTPIN (-4425 1650) SIG_NAME GND\g
J 0
(-4415 1660);
DISPLAY 0.659574 (-4415 1660);
PAINT MONO (-4415 1660);
DISPLAY INVISIBLE (-4415 1660);
FORCEPROP 2 LAST CDS_LIB pure_quanta_power
J 0
(-4425 1600);
PAINT MONO (-4425 1600);
DISPLAY INVISIBLE (-4425 1600);
FORCEPROP 1 LAST PATH I301
J 0
(-4350 1600);
DISPLAY 0.872340 (-4350 1600);
PAINT AQUA (-4350 1600);
DISPLAY INVISIBLE (-4350 1600);
FORCEPROP 1 LAST HDL_POWER GND
J 1
(-4400 1525);
DISPLAY 0.872340 (-4400 1525);
PAINT GREEN (-4400 1525);
DISPLAY INVISIBLE (-4400 1525);
FORCEADD 74HC4052PW..1
(-4825 2100);
FORCEPROP 1 LAST LOCATION U212
J 0
(-5002 2707);
DISPLAY 0.489362 (-5002 2707);
PAINT SKYBLUE (-5002 2707);
FORCEPROP 0 LAST $SEC 1
J 0
(-5000 2850);
DISPLAY 0.680851 (-5000 2850);
PAINT MONO (-5000 2850);
DISPLAY INVISIBLE (-5000 2850);
FORCEPROP 0 LAST CDS_SEC 1
J 0
(-5000 2850);
DISPLAY 1.021277 (-5000 2850);
DISPLAY INVISIBLE (-5000 2850);
FORCEPROP 0 LASTPIN (-4500 2225) $PN 12
J 0
(-4490 2235);
DISPLAY 0.489362 (-4490 2235);
PAINT MONO (-4490 2235);
FORCEPROP 0 LASTPIN (-4500 2275) $PN 14
J 0
(-4490 2285);
DISPLAY 0.489362 (-4490 2285);
PAINT MONO (-4490 2285);
FORCEPROP 0 LASTPIN (-4500 2325) $PN 15
J 0
(-4490 2335);
DISPLAY 0.489362 (-4490 2335);
PAINT MONO (-4490 2335);
FORCEPROP 0 LASTPIN (-4500 2375) $PN 11
J 0
(-4490 2385);
DISPLAY 0.489362 (-4490 2385);
PAINT MONO (-4490 2385);
FORCEPROP 0 LASTPIN (-5150 2325) $PN 13
J 2
(-5160 2335);
DISPLAY 0.489362 (-5160 2335);
PAINT MONO (-5160 2335);
FORCEPROP 0 LASTPIN (-4500 1975) $PN 1
J 0
(-4490 1985);
DISPLAY 0.489362 (-4490 1985);
PAINT MONO (-4490 1985);
FORCEPROP 0 LASTPIN (-4500 2025) $PN 5
J 0
(-4490 2035);
DISPLAY 0.489362 (-4490 2035);
PAINT MONO (-4490 2035);
FORCEPROP 0 LASTPIN (-4500 2075) $PN 2
J 0
(-4490 2085);
DISPLAY 0.489362 (-4490 2085);
PAINT MONO (-4490 2085);
FORCEPROP 0 LASTPIN (-4500 2125) $PN 4
J 0
(-4490 2135);
DISPLAY 0.489362 (-4490 2135);
PAINT MONO (-4490 2135);
FORCEPROP 0 LASTPIN (-5150 2125) $PN 3
J 2
(-5160 2135);
DISPLAY 0.489362 (-5160 2135);
PAINT MONO (-5160 2135);
FORCEPROP 0 LASTPIN (-5150 1875) $PN 6
J 2
(-5160 1885);
DISPLAY 0.489362 (-5160 1885);
PAINT MONO (-5160 1885);
FORCEPROP 0 LASTPIN (-4500 1825) $PN 8
J 0
(-4490 1835);
DISPLAY 0.489362 (-4490 1835);
PAINT MONO (-4490 1835);
FORCEPROP 0 LASTPIN (-5150 1925) $PN 10
J 2
(-5160 1935);
DISPLAY 0.489362 (-5160 1935);
PAINT MONO (-5160 1935);
FORCEPROP 0 LASTPIN (-5150 1975) $PN 9
J 2
(-5160 1985);
DISPLAY 0.489362 (-5160 1985);
PAINT MONO (-5160 1985);
FORCEPROP 0 LASTPIN (-5150 2375) $PN 16
J 2
(-5160 2385);
DISPLAY 0.489362 (-5160 2385);
PAINT MONO (-5160 2385);
FORCEPROP 0 LASTPIN (-4500 1875) $PN 7
J 0
(-4490 1885);
DISPLAY 0.489362 (-4490 1885);
PAINT MONO (-4490 1885);
FORCEPROP 2 LAST PART_TYPE SMLF
J 0
(-5000 2800);
DISPLAY 1.021277 (-5000 2800);
FORCEPROP 1 LAST MATERIAL IC
J 0
(-5002 2433);
DISPLAY 0.489362 (-5002 2433);
PAINT SKYBLUE (-5002 2433);
FORCEPROP 2 LAST VALUE 74HC4052PW
J 0
(-5000 2750);
DISPLAY 0.489362 (-5000 2750);
PAINT SKYBLUE (-5000 2750);
FORCEPROP 1 LAST PART_NUMBER ALHC4052K07
J 0
(-5002 2560);
DISPLAY 0.489362 (-5002 2560);
PAINT SKYBLUE (-5002 2560);
FORCEPROP 1 LAST CDS_LMAN_SYM_OUTLINE -175,325,175,-325
J 0
(-4825 2100);
DISPLAY 0.468085 (-4825 2100);
PAINT GREEN (-4825 2100);
DISPLAY INVISIBLE (-4825 2100);
FORCEPROP 1 LAST NEEDS_NO_SIZE TRUE
J 0
(-4825 2100);
DISPLAY 0.723404 (-4825 2100);
PAINT GREEN (-4825 2100);
DISPLAY INVISIBLE (-4825 2100);
FORCEPROP 2 LAST CDS_LIB pure_quanta
J 0
(-4825 2100);
DISPLAY INVISIBLE (-4825 2100);
FORCEPROP 1 LAST PATH I302
J 0
(-4825 2100);
DISPLAY 0.723404 (-4825 2100);
PAINT GREEN (-4825 2100);
DISPLAY INVISIBLE (-4825 2100);
FORCEADD Q_RES..2
(-7700 4150);
FORCEPROP 1 LAST LOCATION R1730
J 0
(-7625 4300);
DISPLAY 0.489362 (-7625 4300);
PAINT SKYBLUE (-7625 4300);
FORCEPROP 0 LAST $SEC 1
J 0
(-7625 4350);
PAINT MONO (-7625 4350);
DISPLAY INVISIBLE (-7625 4350);
FORCEPROP 0 LAST CDS_SEC 1
J 0
(-7625 4350);
PAINT MONO (-7625 4350);
DISPLAY INVISIBLE (-7625 4350);
FORCEPROP 1 LASTPIN (-7700 4250) $PN 1
J 0
(-7695 4212);
DISPLAY 0.489362 (-7695 4212);
PAINT GREEN (-7695 4212);
FORCEPROP 1 LASTPIN (-7700 4050) $PN 2
J 0
(-7695 4060);
DISPLAY 0.489362 (-7695 4060);
PAINT GREEN (-7695 4060);
FORCEPROP 1 LAST WATTAGE 1/16W
J 0
(-7625 4100);
DISPLAY 0.489362 (-7625 4100);
PAINT SKYBLUE (-7625 4100);
FORCEPROP 1 LAST MATERIAL EMPTY
J 0
(-7630 4200);
DISPLAY 0.489362 (-7630 4200);
PAINT RED (-7630 4200);
FORCEPROP 1 LAST TOLERANCE 5%
J 0
(-7625 4150);
DISPLAY 0.489362 (-7625 4150);
PAINT SKYBLUE (-7625 4150);
FORCEPROP 1 LAST VALUE 4.7K
J 0
(-7625 4250);
DISPLAY 0.489362 (-7625 4250);
PAINT SKYBLUE (-7625 4250);
FORCEPROP 1 LAST PART_NUMBER TMP_QCS24702JB38
J 0
(-7625 4000);
DISPLAY 0.489362 (-7625 4000);
PAINT SKYBLUE (-7625 4000);
FORCEPROP 1 LAST PACK_TYPE 0402LF
J 0
(-7625 4050);
DISPLAY 0.489362 (-7625 4050);
PAINT SKYBLUE (-7625 4050);
FORCEPROP 2 LAST CDS_LIB pure_quanta
J 0
(-7700 4150);
PAINT MONO (-7700 4150);
DISPLAY INVISIBLE (-7700 4150);
FORCEPROP 1 LAST PATH I305
J 0
(-7650 4325);
DISPLAY 0.978723 (-7650 4325);
PAINT WHITE (-7650 4325);
DISPLAY INVISIBLE (-7650 4325);
FORCEADD Q_RES..2
(-7750 3650);
FORCEPROP 1 LAST LOCATION R1729
J 0
(-7675 3800);
DISPLAY 0.489362 (-7675 3800);
PAINT SKYBLUE (-7675 3800);
FORCEPROP 0 LAST $SEC 1
J 0
(-7675 3850);
PAINT MONO (-7675 3850);
DISPLAY INVISIBLE (-7675 3850);
FORCEPROP 0 LAST CDS_SEC 1
J 0
(-7675 3850);
PAINT MONO (-7675 3850);
DISPLAY INVISIBLE (-7675 3850);
FORCEPROP 1 LASTPIN (-7750 3750) $PN 1
J 0
(-7745 3712);
DISPLAY 0.489362 (-7745 3712);
PAINT GREEN (-7745 3712);
FORCEPROP 1 LASTPIN (-7750 3550) $PN 2
J 0
(-7745 3560);
DISPLAY 0.489362 (-7745 3560);
PAINT GREEN (-7745 3560);
FORCEPROP 1 LAST WATTAGE 1/16W
J 0
(-7675 3600);
DISPLAY 0.489362 (-7675 3600);
PAINT SKYBLUE (-7675 3600);
FORCEPROP 1 LAST MATERIAL CHIP
J 0
(-7680 3700);
DISPLAY 0.489362 (-7680 3700);
PAINT SKYBLUE (-7680 3700);
FORCEPROP 1 LAST TOLERANCE 5%
J 0
(-7675 3650);
DISPLAY 0.489362 (-7675 3650);
PAINT SKYBLUE (-7675 3650);
FORCEPROP 1 LAST VALUE 4.7K
J 0
(-7675 3750);
DISPLAY 0.489362 (-7675 3750);
PAINT SKYBLUE (-7675 3750);
FORCEPROP 1 LAST PART_NUMBER TMP_QCS24702JB38
J 0
(-7675 3500);
DISPLAY 0.489362 (-7675 3500);
PAINT SKYBLUE (-7675 3500);
FORCEPROP 1 LAST PACK_TYPE 0402LF
J 0
(-7675 3550);
DISPLAY 0.489362 (-7675 3550);
PAINT SKYBLUE (-7675 3550);
FORCEPROP 2 LAST CDS_LIB pure_quanta
J 0
(-7750 3650);
PAINT MONO (-7750 3650);
DISPLAY INVISIBLE (-7750 3650);
FORCEPROP 1 LAST PATH I306
J 0
(-7700 3825);
DISPLAY 0.978723 (-7700 3825);
PAINT WHITE (-7700 3825);
DISPLAY INVISIBLE (-7700 3825);
FORCEADD UNIVERSAL_GND..1
(-7750 3400);
FORCEPROP 3 LASTPIN (-7750 3450) SIG_NAME GND\g
J 0
(-7740 3460);
DISPLAY 0.659574 (-7740 3460);
PAINT MONO (-7740 3460);
DISPLAY INVISIBLE (-7740 3460);
FORCEPROP 2 LAST CDS_LIB pure_quanta_power
J 0
(-7750 3400);
PAINT MONO (-7750 3400);
DISPLAY INVISIBLE (-7750 3400);
FORCEPROP 1 LAST PATH I307
J 0
(-7675 3400);
DISPLAY 0.872340 (-7675 3400);
PAINT AQUA (-7675 3400);
DISPLAY INVISIBLE (-7675 3400);
FORCEPROP 1 LAST HDL_POWER GND
J 1
(-7725 3325);
DISPLAY 0.872340 (-7725 3325);
PAINT GREEN (-7725 3325);
DISPLAY INVISIBLE (-7725 3325);
FORCEADD UNIVERSAL_POWER..1
(-7700 2375);
FORCEPROP 3 LASTPIN (-7700 2325) SIG_NAME P3V3_STBY\g
J 0
(-7690 2335);
DISPLAY 0.659574 (-7690 2335);
PAINT MONO (-7690 2335);
DISPLAY INVISIBLE (-7690 2335);
FORCEPROP 1 LAST HDL_POWER P3V3_STBY
J 1
(-7700 2425);
DISPLAY 0.489362 (-7700 2425);
PAINT GREEN (-7700 2425);
FORCEPROP 2 LAST CDS_LIB pure_quanta_power
J 0
(-7700 2375);
DISPLAY INVISIBLE (-7700 2375);
FORCEPROP 1 LAST PATH I308
J 0
(-7650 2400);
DISPLAY 0.872340 (-7650 2400);
PAINT AQUA (-7650 2400);
DISPLAY INVISIBLE (-7650 2400);
FORCEADD Q_RES..2
(-7700 2150);
FORCEPROP 1 LAST LOCATION R1659
J 0
(-7655 2275);
DISPLAY 0.489362 (-7655 2275);
PAINT SKYBLUE (-7655 2275);
FORCEPROP 0 LAST $SEC 1
J 0
(-7650 2325);
DISPLAY 0.680851 (-7650 2325);
PAINT MONO (-7650 2325);
DISPLAY INVISIBLE (-7650 2325);
FORCEPROP 0 LAST CDS_SEC 1
J 0
(-7650 2325);
DISPLAY 1.021277 (-7650 2325);
DISPLAY INVISIBLE (-7650 2325);
FORCEPROP 1 LASTPIN (-7700 2250) $PN 1
J 0
(-7695 2212);
DISPLAY 0.489362 (-7695 2212);
PAINT MONO (-7695 2212);
FORCEPROP 1 LASTPIN (-7700 2050) $PN 2
J 0
(-7695 2060);
DISPLAY 0.489362 (-7695 2060);
PAINT MONO (-7695 2060);
FORCEPROP 1 LAST WATTAGE 1/16W
J 0
(-7625 2100);
DISPLAY 0.489362 (-7625 2100);
PAINT SKYBLUE (-7625 2100);
FORCEPROP 1 LAST MATERIAL EMPTY
J 0
(-7630 2200);
DISPLAY 0.489362 (-7630 2200);
PAINT RED (-7630 2200);
FORCEPROP 1 LAST TOLERANCE 5%
J 0
(-7625 2150);
DISPLAY 0.489362 (-7625 2150);
PAINT SKYBLUE (-7625 2150);
FORCEPROP 1 LAST VALUE 4.7K
J 0
(-7625 2250);
DISPLAY 0.489362 (-7625 2250);
PAINT SKYBLUE (-7625 2250);
FORCEPROP 1 LAST PART_NUMBER TMP_QCS24702JB38
J 0
(-7625 2000);
DISPLAY 0.489362 (-7625 2000);
PAINT SKYBLUE (-7625 2000);
FORCEPROP 1 LAST PACK_TYPE 0402LF
J 0
(-7625 2050);
DISPLAY 0.489362 (-7625 2050);
PAINT SKYBLUE (-7625 2050);
FORCEPROP 2 LAST CDS_LIB pure_quanta
J 0
(-7700 2150);
DISPLAY INVISIBLE (-7700 2150);
FORCEPROP 1 LAST PATH I309
J 0
(-7650 2325);
DISPLAY 0.978723 (-7650 2325);
PAINT WHITE (-7650 2325);
DISPLAY INVISIBLE (-7650 2325);
FORCEADD Q_RES..2
(-7750 1650);
FORCEPROP 1 LAST LOCATION R1658
J 0
(-7705 1775);
DISPLAY 0.489362 (-7705 1775);
PAINT SKYBLUE (-7705 1775);
FORCEPROP 0 LAST $SEC 1
J 0
(-7700 1825);
DISPLAY 0.680851 (-7700 1825);
PAINT MONO (-7700 1825);
DISPLAY INVISIBLE (-7700 1825);
FORCEPROP 0 LAST CDS_SEC 1
J 0
(-7700 1825);
DISPLAY 1.021277 (-7700 1825);
DISPLAY INVISIBLE (-7700 1825);
FORCEPROP 1 LASTPIN (-7750 1750) $PN 1
J 0
(-7745 1712);
DISPLAY 0.489362 (-7745 1712);
PAINT MONO (-7745 1712);
FORCEPROP 1 LASTPIN (-7750 1550) $PN 2
J 0
(-7745 1560);
DISPLAY 0.489362 (-7745 1560);
PAINT MONO (-7745 1560);
FORCEPROP 1 LAST WATTAGE 1/16W
J 0
(-7675 1600);
DISPLAY 0.489362 (-7675 1600);
PAINT SKYBLUE (-7675 1600);
FORCEPROP 1 LAST MATERIAL CHIP
J 0
(-7680 1700);
DISPLAY 0.489362 (-7680 1700);
PAINT SKYBLUE (-7680 1700);
FORCEPROP 1 LAST TOLERANCE 5%
J 0
(-7675 1650);
DISPLAY 0.489362 (-7675 1650);
PAINT SKYBLUE (-7675 1650);
FORCEPROP 1 LAST VALUE 4.7K
J 0
(-7675 1750);
DISPLAY 0.489362 (-7675 1750);
PAINT SKYBLUE (-7675 1750);
FORCEPROP 1 LAST PART_NUMBER TMP_QCS24702JB38
J 0
(-7675 1500);
DISPLAY 0.489362 (-7675 1500);
PAINT SKYBLUE (-7675 1500);
FORCEPROP 1 LAST PACK_TYPE 0402LF
J 0
(-7675 1550);
DISPLAY 0.489362 (-7675 1550);
PAINT SKYBLUE (-7675 1550);
FORCEPROP 2 LAST CDS_LIB pure_quanta
J 0
(-7750 1650);
DISPLAY INVISIBLE (-7750 1650);
FORCEPROP 1 LAST PATH I310
J 0
(-7700 1825);
DISPLAY 0.978723 (-7700 1825);
PAINT WHITE (-7700 1825);
DISPLAY INVISIBLE (-7700 1825);
FORCEADD UNIVERSAL_GND..1
(-7750 1400);
FORCEPROP 3 LASTPIN (-7750 1450) SIG_NAME GND\g
J 0
(-7740 1460);
DISPLAY 0.659574 (-7740 1460);
PAINT MONO (-7740 1460);
DISPLAY INVISIBLE (-7740 1460);
FORCEPROP 2 LAST CDS_LIB pure_quanta_power
J 0
(-7750 1400);
DISPLAY INVISIBLE (-7750 1400);
FORCEPROP 1 LAST PATH I311
J 0
(-7675 1400);
DISPLAY 0.872340 (-7675 1400);
PAINT AQUA (-7675 1400);
DISPLAY INVISIBLE (-7675 1400);
FORCEPROP 1 LAST HDL_POWER GND
J 1
(-7725 1325);
DISPLAY 0.872340 (-7725 1325);
PAINT GREEN (-7725 1325);
DISPLAY INVISIBLE (-7725 1325);
FORCEADD OFFPAGE..1
(-8050 3925);
FORCEPROP 2 LAST $XR0 79 
J 0
(-8301 3925);
DISPLAY 0.638298 (-8301 3925);
PAINT MONO (-8301 3925);
FORCEPROP 2 LAST CDS_LIB standard
J 0
(-8050 3925);
DISPLAY INVISIBLE (-8050 3925);
FORCEPROP 1 LAST OFFPAGE TRUE
J 0
(-7725 3800);
DISPLAY 0.872340 (-7725 3800);
PAINT GREEN (-7725 3800);
DISPLAY INVISIBLE (-7725 3800);
FORCEPROP 1 LAST COMMENT_BODY TRUE
J 0
(-7925 3825);
DISPLAY 0.872340 (-7925 3825);
PAINT GREEN (-7925 3825);
DISPLAY INVISIBLE (-7925 3825);
FORCEPROP 2 LAST PATH I312
J 0
(-8000 4000);
DISPLAY 1.021277 (-8000 4000);
DISPLAY INVISIBLE (-8000 4000);
FORCEADD OFFPAGE..1
(-8050 1925);
FORCEPROP 2 LAST $XR0 79 
J 0
(-8301 1925);
DISPLAY 0.638298 (-8301 1925);
PAINT MONO (-8301 1925);
FORCEPROP 2 LAST CDS_LIB standard
J 0
(-8050 1925);
DISPLAY INVISIBLE (-8050 1925);
FORCEPROP 1 LAST OFFPAGE TRUE
J 0
(-7725 1800);
DISPLAY 0.872340 (-7725 1800);
PAINT GREEN (-7725 1800);
DISPLAY INVISIBLE (-7725 1800);
FORCEPROP 1 LAST COMMENT_BODY TRUE
J 0
(-7925 1825);
DISPLAY 0.872340 (-7925 1825);
PAINT GREEN (-7925 1825);
DISPLAY INVISIBLE (-7925 1825);
FORCEPROP 2 LAST PATH I313
J 0
(-8000 2000);
DISPLAY 1.021277 (-8000 2000);
DISPLAY INVISIBLE (-8000 2000);
FORCEADD OFFPAGE..5
(-5925 2325);
FORCEPROP 2 LAST $XR1 117 
J 0
(-6330 2325);
DISPLAY 0.638298 (-6330 2325);
PAINT MONO (-6330 2325);
FORCEPROP 2 LAST $XR0 148 
J 0
(-6210 2325);
DISPLAY 0.638298 (-6210 2325);
PAINT MONO (-6210 2325);
FORCEPROP 2 LAST CDS_LIB standard
J 2
(-5925 2325);
DISPLAY INVISIBLE (-5925 2325);
FORCEPROP 1 LAST OFFPAGE TRUE
J 0
(-5600 2200);
DISPLAY 0.872340 (-5600 2200);
PAINT GREEN (-5600 2200);
DISPLAY INVISIBLE (-5600 2200);
FORCEPROP 1 LAST COMMENT_BODY TRUE
J 0
(-5825 2250);
DISPLAY 0.872340 (-5825 2250);
PAINT GREEN (-5825 2250);
DISPLAY INVISIBLE (-5825 2250);
FORCEPROP 2 LAST PATH I314
J 0
(-6200 2375);
DISPLAY 1.021277 (-6200 2375);
DISPLAY INVISIBLE (-6200 2375);
FORCEADD OFFPAGE..4
R 2
(-5925 2125);
FORCEPROP 2 LAST $XR1 148 
J 0
(-6297 2125);
DISPLAY 0.638298 (-6297 2125);
PAINT MONO (-6297 2125);
FORCEPROP 2 LAST $XR0 117 
J 0
(-6177 2125);
DISPLAY 0.638298 (-6177 2125);
PAINT MONO (-6177 2125);
FORCEPROP 2 LAST CDS_LIB standard
J 0
(-5925 2125);
DISPLAY INVISIBLE (-5925 2125);
FORCEPROP 1 LAST OFFPAGE TRUE
J 2
(-6250 2000);
DISPLAY 0.872340 (-6250 2000);
PAINT GREEN (-6250 2000);
DISPLAY INVISIBLE (-6250 2000);
FORCEPROP 1 LAST COMMENT_BODY TRUE
J 2
(-5900 2025);
DISPLAY 0.872340 (-5900 2025);
PAINT GREEN (-5900 2025);
DISPLAY INVISIBLE (-5900 2025);
FORCEPROP 2 LAST PATH I315
J 0
(-6175 2175);
DISPLAY 1.021277 (-6175 2175);
DISPLAY INVISIBLE (-6175 2175);
FORCEADD OFFPAGE..5
R 2
(-1975 2025);
FORCEPROP 2 LAST $XR1 149 
J 0
(-1666 2025);
DISPLAY 0.638298 (-1666 2025);
PAINT MONO (-1666 2025);
FORCEPROP 2 LAST $XR0 148 
J 0
(-1786 2025);
DISPLAY 0.638298 (-1786 2025);
PAINT MONO (-1786 2025);
FORCEPROP 2 LAST CDS_LIB standard
J 0
(-1975 2025);
DISPLAY INVISIBLE (-1975 2025);
FORCEPROP 1 LAST OFFPAGE TRUE
J 2
(-2300 1900);
DISPLAY 0.872340 (-2300 1900);
PAINT GREEN (-2300 1900);
DISPLAY INVISIBLE (-2300 1900);
FORCEPROP 1 LAST COMMENT_BODY TRUE
J 2
(-2075 1950);
DISPLAY 0.872340 (-2075 1950);
PAINT GREEN (-2075 1950);
DISPLAY INVISIBLE (-2075 1950);
FORCEPROP 2 LAST PATH I327
J 0
(-1650 2075);
DISPLAY 0.680851 (-1650 2075);
DISPLAY INVISIBLE (-1650 2075);
FORCEADD Q_RES..1
(-3200 2025);
FORCEPROP 1 LAST LOCATION R1739
J 0
(-3650 2025);
DISPLAY 0.489362 (-3650 2025);
PAINT SKYBLUE (-3650 2025);
FORCEPROP 0 LAST $SEC 1
J 0
(-3450 2075);
PAINT MONO (-3450 2075);
DISPLAY INVISIBLE (-3450 2075);
FORCEPROP 0 LAST CDS_SEC 1
J 0
(-3450 2075);
PAINT MONO (-3450 2075);
DISPLAY INVISIBLE (-3450 2075);
FORCEPROP 1 LASTPIN (-3300 2025) $PN 1
J 0
(-3288 2037);
DISPLAY 0.489362 (-3288 2037);
PAINT GREEN (-3288 2037);
FORCEPROP 1 LASTPIN (-3100 2025) $PN 2
J 0
(-3138 2037);
DISPLAY 0.489362 (-3138 2037);
PAINT GREEN (-3138 2037);
FORCEPROP 1 LAST MATERIAL CHIP
J 0
(-3375 2000);
DISPLAY 0.489362 (-3375 2000);
PAINT SKYBLUE (-3375 2000);
FORCEPROP 1 LAST TOLERANCE 1%
J 0
(-3100 2000);
DISPLAY 0.489362 (-3100 2000);
PAINT SKYBLUE (-3100 2000);
FORCEPROP 1 LAST VALUE 22
J 2
(-3300 2025);
DISPLAY 0.489362 (-3300 2025);
PAINT SKYBLUE (-3300 2025);
FORCEPROP 2 LAST CDS_LIB pure_quanta
J 0
(-3200 2025);
PAINT MONO (-3200 2025);
DISPLAY INVISIBLE (-3200 2025);
FORCEPROP 1 LAST PATH I329
J 0
(-3250 2175);
DISPLAY 0.978723 (-3250 2175);
PAINT WHITE (-3250 2175);
DISPLAY INVISIBLE (-3250 2175);
FORCEPROP 1 LAST WATTAGE 1/16W
J 2
(-3225 1875);
DISPLAY 0.978723 (-3225 1875);
PAINT SKYBLUE (-3225 1875);
DISPLAY INVISIBLE (-3225 1875);
FORCEPROP 1 LAST PART_NUMBER CS02202FB12
J 0
(-3250 2125);
DISPLAY 0.978723 (-3250 2125);
PAINT SKYBLUE (-3250 2125);
DISPLAY INVISIBLE (-3250 2125);
FORCEPROP 1 LAST PACK_TYPE 0402LF
J 0
(-2950 1875);
DISPLAY 0.978723 (-2950 1875);
PAINT SKYBLUE (-2950 1875);
DISPLAY INVISIBLE (-2950 1875);
FORCEADD OFFPAGE..5
R 2
(-1975 2075);
FORCEPROP 2 LAST $XR1 79 
J 0
(-1696 2075);
DISPLAY 0.638298 (-1696 2075);
PAINT MONO (-1696 2075);
FORCEPROP 2 LAST $XR0 84 
J 0
(-1786 2075);
DISPLAY 0.638298 (-1786 2075);
PAINT MONO (-1786 2075);
FORCEPROP 2 LAST CDS_LIB standard
J 0
(-1975 2075);
DISPLAY INVISIBLE (-1975 2075);
FORCEPROP 1 LAST OFFPAGE TRUE
J 2
(-2300 1950);
DISPLAY 0.872340 (-2300 1950);
PAINT GREEN (-2300 1950);
DISPLAY INVISIBLE (-2300 1950);
FORCEPROP 1 LAST COMMENT_BODY TRUE
J 2
(-2075 2000);
DISPLAY 0.872340 (-2075 2000);
PAINT GREEN (-2075 2000);
DISPLAY INVISIBLE (-2075 2000);
FORCEPROP 2 LAST PATH I331
J 0
(-1775 2125);
DISPLAY 0.680851 (-1775 2125);
DISPLAY INVISIBLE (-1775 2125);
FORCEADD Q_RES..1
(-3200 2075);
FORCEPROP 1 LAST LOCATION R1743
J 0
(-3650 2075);
DISPLAY 0.489362 (-3650 2075);
PAINT SKYBLUE (-3650 2075);
FORCEPROP 0 LAST $SEC 1
J 0
(-3450 2125);
PAINT MONO (-3450 2125);
DISPLAY INVISIBLE (-3450 2125);
FORCEPROP 0 LAST CDS_SEC 1
J 0
(-3450 2125);
PAINT MONO (-3450 2125);
DISPLAY INVISIBLE (-3450 2125);
FORCEPROP 1 LASTPIN (-3300 2075) $PN 1
J 0
(-3288 2087);
DISPLAY 0.489362 (-3288 2087);
PAINT GREEN (-3288 2087);
FORCEPROP 1 LASTPIN (-3100 2075) $PN 2
J 0
(-3138 2087);
DISPLAY 0.489362 (-3138 2087);
PAINT GREEN (-3138 2087);
FORCEPROP 1 LAST MATERIAL CHIP
J 0
(-3375 2050);
DISPLAY 0.489362 (-3375 2050);
PAINT SKYBLUE (-3375 2050);
FORCEPROP 1 LAST TOLERANCE 1%
J 0
(-3100 2050);
DISPLAY 0.489362 (-3100 2050);
PAINT SKYBLUE (-3100 2050);
FORCEPROP 1 LAST VALUE 22
J 2
(-3300 2075);
DISPLAY 0.489362 (-3300 2075);
PAINT SKYBLUE (-3300 2075);
FORCEPROP 2 LAST CDS_LIB pure_quanta
J 0
(-3200 2075);
PAINT MONO (-3200 2075);
DISPLAY INVISIBLE (-3200 2075);
FORCEPROP 1 LAST PATH I332
J 0
(-3250 2225);
DISPLAY 0.978723 (-3250 2225);
PAINT WHITE (-3250 2225);
DISPLAY INVISIBLE (-3250 2225);
FORCEPROP 1 LAST WATTAGE 1/16W
J 2
(-3225 1925);
DISPLAY 0.978723 (-3225 1925);
PAINT SKYBLUE (-3225 1925);
DISPLAY INVISIBLE (-3225 1925);
FORCEPROP 1 LAST PART_NUMBER CS02202FB12
J 0
(-3250 2175);
DISPLAY 0.978723 (-3250 2175);
PAINT SKYBLUE (-3250 2175);
DISPLAY INVISIBLE (-3250 2175);
FORCEPROP 1 LAST PACK_TYPE 0402LF
J 0
(-2950 1925);
DISPLAY 0.978723 (-2950 1925);
PAINT SKYBLUE (-2950 1925);
DISPLAY INVISIBLE (-2950 1925);
FORCEADD OFFPAGE..1
(-9000 5225);
FORCEPROP 2 LAST $XR0 117 
J 0
(-9252 5225);
DISPLAY 0.638298 (-9252 5225);
PAINT MONO (-9252 5225);
FORCEPROP 2 LAST CDS_LIB standard
J 0
(-9000 5225);
DISPLAY INVISIBLE (-9000 5225);
FORCEPROP 1 LAST OFFPAGE TRUE
J 0
(-8675 5100);
DISPLAY 0.872340 (-8675 5100);
PAINT GREEN (-8675 5100);
DISPLAY INVISIBLE (-8675 5100);
FORCEPROP 1 LAST COMMENT_BODY TRUE
J 0
(-8875 5125);
DISPLAY 0.872340 (-8875 5125);
PAINT GREEN (-8875 5125);
DISPLAY INVISIBLE (-8875 5125);
FORCEPROP 2 LAST PATH I336
J 0
(-8950 5300);
DISPLAY 0.680851 (-8950 5300);
DISPLAY INVISIBLE (-8950 5300);
FORCEADD UNIVERSAL_POWER..1
(-6575 5775);
FORCEPROP 3 LASTPIN (-6575 5725) SIG_NAME P3V3_STBY\g
J 0
(-6565 5735);
DISPLAY 0.659574 (-6565 5735);
PAINT MONO (-6565 5735);
DISPLAY INVISIBLE (-6565 5735);
FORCEPROP 1 LAST HDL_POWER P3V3_STBY
J 1
(-6575 5825);
DISPLAY 0.489362 (-6575 5825);
PAINT GREEN (-6575 5825);
FORCEPROP 2 LAST CDS_LIB pure_quanta_power
J 0
(-6575 5775);
DISPLAY INVISIBLE (-6575 5775);
FORCEPROP 2 LAST BOM_COST OCP3.0 
J 0
(-6575 5875);
DISPLAY 0.680851 (-6575 5875);
DISPLAY INVISIBLE (-6575 5875);
FORCEPROP 1 LAST PATH I337
J 0
(-6525 5800);
DISPLAY 0.872340 (-6525 5800);
PAINT AQUA (-6525 5800);
DISPLAY INVISIBLE (-6525 5800);
FORCEADD Q_RES..2
(-6575 5500);
FORCEPROP 1 LAST LOCATION R1343
J 0
(-6530 5625);
DISPLAY 0.489362 (-6530 5625);
PAINT SKYBLUE (-6530 5625);
FORCEPROP 0 LAST $SEC 1
J 0
(-6525 5675);
DISPLAY 0.680851 (-6525 5675);
PAINT MONO (-6525 5675);
DISPLAY INVISIBLE (-6525 5675);
FORCEPROP 0 LAST CDS_SEC 1
J 0
(-6525 5675);
DISPLAY 0.680851 (-6525 5675);
DISPLAY INVISIBLE (-6525 5675);
FORCEPROP 1 LASTPIN (-6575 5600) $PN 1
J 0
(-6570 5562);
DISPLAY 0.489362 (-6570 5562);
PAINT MONO (-6570 5562);
FORCEPROP 1 LASTPIN (-6575 5400) $PN 2
J 0
(-6570 5410);
DISPLAY 0.489362 (-6570 5410);
PAINT MONO (-6570 5410);
FORCEPROP 1 LAST WATTAGE 1/16W
J 0
(-6535 5475);
DISPLAY 0.489362 (-6535 5475);
PAINT SKYBLUE (-6535 5475);
FORCEPROP 1 LAST MATERIAL EMPTY
J 0
(-6535 5425);
DISPLAY 0.489362 (-6535 5425);
PAINT RED (-6535 5425);
FORCEPROP 1 LAST TOLERANCE 5%
J 0
(-6530 5525);
DISPLAY 0.489362 (-6530 5525);
PAINT SKYBLUE (-6530 5525);
FORCEPROP 1 LAST VALUE 4.7K
J 0
(-6530 5575);
DISPLAY 0.489362 (-6530 5575);
PAINT SKYBLUE (-6530 5575);
FORCEPROP 1 LAST PART_NUMBER TMP_QCS24702JB38
J 0
(-6535 5375);
DISPLAY 0.489362 (-6535 5375);
PAINT SKYBLUE (-6535 5375);
FORCEPROP 1 LAST PACK_TYPE 0402LF
J 0
(-6535 5325);
DISPLAY 0.489362 (-6535 5325);
PAINT SKYBLUE (-6535 5325);
FORCEPROP 2 LAST BOM_COST OCP3.0 
J 0
(-6525 5675);
DISPLAY 0.680851 (-6525 5675);
DISPLAY INVISIBLE (-6525 5675);
FORCEPROP 2 LAST CDS_LIB pure_quanta
J 0
(-6575 5500);
DISPLAY INVISIBLE (-6575 5500);
FORCEPROP 1 LAST PATH I339
J 0
(-6525 5675);
DISPLAY 0.978723 (-6525 5675);
PAINT WHITE (-6525 5675);
DISPLAY INVISIBLE (-6525 5675);
FORCEADD SN74LVC1G07DBVR..1
(-7400 5225);
FORCEPROP 1 LAST LOCATION U99
J 0
(-7525 5480);
DISPLAY 0.489362 (-7525 5480);
PAINT SKYBLUE (-7525 5480);
FORCEPROP 0 LAST $SEC 1
J 0
(-7525 5625);
DISPLAY 0.680851 (-7525 5625);
PAINT MONO (-7525 5625);
DISPLAY INVISIBLE (-7525 5625);
FORCEPROP 0 LAST CDS_SEC 1
J 0
(-7525 5625);
DISPLAY 0.680851 (-7525 5625);
DISPLAY INVISIBLE (-7525 5625);
FORCEPROP 0 LASTPIN (-7575 5225) $PN 2
J 2
(-7585 5235);
DISPLAY 0.489362 (-7585 5235);
PAINT MONO (-7585 5235);
FORCEPROP 0 LASTPIN (-7575 5125) $PN 3
J 2
(-7585 5135);
DISPLAY 0.489362 (-7585 5135);
PAINT MONO (-7585 5135);
FORCEPROP 0 LASTPIN (-7225 5125) $PN 1
J 0
(-7215 5135);
DISPLAY 0.489362 (-7215 5135);
PAINT MONO (-7215 5135);
FORCEPROP 0 LASTPIN (-7575 5325) $PN 5
J 2
(-7585 5335);
DISPLAY 0.489362 (-7585 5335);
PAINT MONO (-7585 5335);
FORCEPROP 0 LASTPIN (-7225 5225) $PN 4
J 0
(-7215 5235);
DISPLAY 0.489362 (-7215 5235);
PAINT MONO (-7215 5235);
FORCEPROP 1 LAST MATERIAL EMPTY
J 0
(-7525 5385);
DISPLAY 0.489362 (-7525 5385);
PAINT RED (-7525 5385);
FORCEPROP 2 LAST VALUE SN74LVC1G07DBVR
J 0
(-7525 5575);
DISPLAY 0.489362 (-7525 5575);
PAINT SKYBLUE (-7525 5575);
FORCEPROP 1 LAST PART_NUMBER AL1G0007024
J 0
(-7525 5435);
DISPLAY 0.489362 (-7525 5435);
PAINT SKYBLUE (-7525 5435);
FORCEPROP 2 LAST PACK_TYPE SMLF
J 0
(-7525 5525);
DISPLAY 0.489362 (-7525 5525);
PAINT SKYBLUE (-7525 5525);
FORCEPROP 1 LAST NEEDS_NO_SIZE TRUE
J 0
(-7400 5225);
DISPLAY 0.468085 (-7400 5225);
PAINT GREEN (-7400 5225);
DISPLAY INVISIBLE (-7400 5225);
FORCEPROP 2 LAST CDS_LIB pure_quanta
J 0
(-7400 5225);
DISPLAY INVISIBLE (-7400 5225);
FORCEPROP 1 LAST PATH I340
J 0
(-7300 5380);
DISPLAY 0.723404 (-7300 5380);
PAINT GREEN (-7300 5380);
DISPLAY INVISIBLE (-7300 5380);
FORCEADD UNIVERSAL_POWER..1
(-8000 5850);
FORCEPROP 3 LASTPIN (-8000 5800) SIG_NAME P3V3_STBY\g
J 0
(-7990 5810);
DISPLAY 0.659574 (-7990 5810);
PAINT MONO (-7990 5810);
DISPLAY INVISIBLE (-7990 5810);
FORCEPROP 1 LAST HDL_POWER P3V3_STBY
J 1
(-8000 5900);
DISPLAY 0.489362 (-8000 5900);
PAINT GREEN (-8000 5900);
FORCEPROP 2 LAST CDS_LIB pure_quanta_power
J 0
(-8000 5850);
DISPLAY INVISIBLE (-8000 5850);
FORCEPROP 2 LAST BOM_COST OCP3.0 
J 0
(-8000 5950);
DISPLAY 0.680851 (-8000 5950);
DISPLAY INVISIBLE (-8000 5950);
FORCEPROP 1 LAST PATH I341
J 0
(-7950 5875);
DISPLAY 0.872340 (-7950 5875);
PAINT AQUA (-7950 5875);
DISPLAY INVISIBLE (-7950 5875);
FORCEADD Q_CAP..1
(-8000 5550);
FORCEPROP 1 LAST LOCATION C553
J 0
(-7950 5650);
DISPLAY 0.489362 (-7950 5650);
PAINT SKYBLUE (-7950 5650);
FORCEPROP 0 LAST $SEC 1
J 0
(-7950 5700);
DISPLAY 0.680851 (-7950 5700);
PAINT MONO (-7950 5700);
DISPLAY INVISIBLE (-7950 5700);
FORCEPROP 0 LAST CDS_SEC 1
J 0
(-7950 5700);
DISPLAY 0.680851 (-7950 5700);
DISPLAY INVISIBLE (-7950 5700);
FORCEPROP 1 LASTPIN (-8000 5650) $PN 1
J 0
(-7990 5630);
DISPLAY 0.489362 (-7990 5630);
PAINT MONO (-7990 5630);
FORCEPROP 1 LASTPIN (-8000 5450) $PN 2
J 0
(-7990 5430);
DISPLAY 0.489362 (-7990 5430);
PAINT MONO (-7990 5430);
FORCEPROP 1 LAST MATERIAL X7R
J 0
(-7925 5475);
DISPLAY 0.489362 (-7925 5475);
PAINT SKYBLUE (-7925 5475);
FORCEPROP 1 LAST TOLERANCE 10%
J 0
(-7925 5525);
DISPLAY 0.489362 (-7925 5525);
PAINT SKYBLUE (-7925 5525);
FORCEPROP 1 LAST VALUE 0.1UF
J 0
(-7925 5625);
DISPLAY 0.489362 (-7925 5625);
PAINT SKYBLUE (-7925 5625);
FORCEPROP 1 LAST PART_NUMBER CH4104K1B00
J 0
(-7925 5425);
DISPLAY 0.489362 (-7925 5425);
PAINT SKYBLUE (-7925 5425);
FORCEPROP 1 LAST VOLTAGE 25V
J 0
(-7925 5575);
DISPLAY 0.489362 (-7925 5575);
PAINT SKYBLUE (-7925 5575);
FORCEPROP 1 LAST PACK_TYPE 0402
J 0
(-7925 5375);
DISPLAY 0.489362 (-7925 5375);
PAINT SKYBLUE (-7925 5375);
FORCEPROP 2 LAST BOM_COST OCP3.0 
J 0
(-7975 5675);
DISPLAY 0.680851 (-7975 5675);
DISPLAY INVISIBLE (-7975 5675);
FORCEPROP 2 LAST CDS_LIB pure_quanta
J 0
(-8000 5550);
DISPLAY INVISIBLE (-8000 5550);
FORCEPROP 1 LAST PATH I342
J 0
(-7950 5700);
DISPLAY 0.978723 (-7950 5700);
PAINT WHITE (-7950 5700);
DISPLAY INVISIBLE (-7950 5700);
FORCEADD UNIVERSAL_GND..1
(-8000 5350);
FORCEPROP 3 LASTPIN (-8000 5400) SIG_NAME GND\g
J 0
(-7990 5410);
DISPLAY 0.659574 (-7990 5410);
PAINT MONO (-7990 5410);
DISPLAY INVISIBLE (-7990 5410);
FORCEPROP 2 LAST CDS_LIB pure_quanta_power
J 0
(-8000 5350);
DISPLAY INVISIBLE (-8000 5350);
FORCEPROP 2 LAST BOM_COST OCP3.0 
J 0
(-8200 5425);
DISPLAY 0.680851 (-8200 5425);
DISPLAY INVISIBLE (-8200 5425);
FORCEPROP 1 LAST PATH I343
J 0
(-7925 5350);
DISPLAY 0.872340 (-7925 5350);
PAINT AQUA (-7925 5350);
DISPLAY INVISIBLE (-7925 5350);
FORCEPROP 1 LAST HDL_POWER GND
J 1
(-7975 5275);
DISPLAY 0.872340 (-7975 5275);
PAINT GREEN (-7975 5275);
DISPLAY INVISIBLE (-7975 5275);
FORCEADD UNIVERSAL_GND..1
(-7650 4950);
FORCEPROP 3 LASTPIN (-7650 5000) SIG_NAME GND\g
J 0
(-7640 5010);
DISPLAY 0.659574 (-7640 5010);
PAINT MONO (-7640 5010);
DISPLAY INVISIBLE (-7640 5010);
FORCEPROP 2 LAST CDS_LIB pure_quanta_power
J 0
(-7650 4950);
DISPLAY INVISIBLE (-7650 4950);
FORCEPROP 1 LAST PATH I344
J 0
(-7575 4950);
DISPLAY 0.872340 (-7575 4950);
PAINT AQUA (-7575 4950);
DISPLAY INVISIBLE (-7575 4950);
FORCEPROP 1 LAST HDL_POWER GND
J 1
(-7625 4875);
DISPLAY 0.872340 (-7625 4875);
PAINT GREEN (-7625 4875);
DISPLAY INVISIBLE (-7625 4875);
FORCEADD OFFPAGE..4
(-1975 2275);
FORCEPROP 2 LAST $XR1 149 
J 0
(-1669 2275);
DISPLAY 0.638298 (-1669 2275);
PAINT MONO (-1669 2275);
FORCEPROP 2 LAST $XR0 148 
J 0
(-1789 2275);
DISPLAY 0.638298 (-1789 2275);
PAINT MONO (-1789 2275);
FORCEPROP 2 LAST CDS_LIB standard
J 0
(-1975 2275);
DISPLAY INVISIBLE (-1975 2275);
FORCEPROP 1 LAST OFFPAGE TRUE
J 0
(-1650 2150);
DISPLAY 0.872340 (-1650 2150);
PAINT GREEN (-1650 2150);
DISPLAY INVISIBLE (-1650 2150);
FORCEPROP 1 LAST COMMENT_BODY TRUE
J 0
(-2000 2175);
DISPLAY 0.872340 (-2000 2175);
PAINT GREEN (-2000 2175);
DISPLAY INVISIBLE (-2000 2175);
FORCEPROP 2 LAST PATH I347
J 0
(-1650 2325);
DISPLAY 0.680851 (-1650 2325);
DISPLAY INVISIBLE (-1650 2325);
FORCEADD Q_RES..1
(-3200 2275);
FORCEPROP 1 LAST LOCATION R1738
J 0
(-3650 2275);
DISPLAY 0.489362 (-3650 2275);
PAINT SKYBLUE (-3650 2275);
FORCEPROP 0 LAST $SEC 1
J 0
(-3450 2325);
PAINT MONO (-3450 2325);
DISPLAY INVISIBLE (-3450 2325);
FORCEPROP 0 LAST CDS_SEC 1
J 0
(-3450 2325);
PAINT MONO (-3450 2325);
DISPLAY INVISIBLE (-3450 2325);
FORCEPROP 1 LASTPIN (-3300 2275) $PN 1
J 0
(-3288 2287);
DISPLAY 0.489362 (-3288 2287);
PAINT GREEN (-3288 2287);
FORCEPROP 1 LASTPIN (-3100 2275) $PN 2
J 0
(-3138 2287);
DISPLAY 0.489362 (-3138 2287);
PAINT GREEN (-3138 2287);
FORCEPROP 1 LAST MATERIAL CHIP
J 0
(-3375 2250);
DISPLAY 0.489362 (-3375 2250);
PAINT SKYBLUE (-3375 2250);
FORCEPROP 1 LAST TOLERANCE 1%
J 0
(-3100 2250);
DISPLAY 0.489362 (-3100 2250);
PAINT SKYBLUE (-3100 2250);
FORCEPROP 1 LAST VALUE 22
J 2
(-3300 2275);
DISPLAY 0.489362 (-3300 2275);
PAINT SKYBLUE (-3300 2275);
FORCEPROP 2 LAST CDS_LIB pure_quanta
J 0
(-3200 2275);
PAINT MONO (-3200 2275);
DISPLAY INVISIBLE (-3200 2275);
FORCEPROP 1 LAST PATH I349
J 0
(-3250 2425);
DISPLAY 0.978723 (-3250 2425);
PAINT WHITE (-3250 2425);
DISPLAY INVISIBLE (-3250 2425);
FORCEPROP 1 LAST WATTAGE 1/16W
J 2
(-3225 2125);
DISPLAY 0.978723 (-3225 2125);
PAINT SKYBLUE (-3225 2125);
DISPLAY INVISIBLE (-3225 2125);
FORCEPROP 1 LAST PART_NUMBER CS02202FB12
J 0
(-3250 2375);
DISPLAY 0.978723 (-3250 2375);
PAINT SKYBLUE (-3250 2375);
DISPLAY INVISIBLE (-3250 2375);
FORCEPROP 1 LAST PACK_TYPE 0402LF
J 0
(-2950 2125);
DISPLAY 0.978723 (-2950 2125);
PAINT SKYBLUE (-2950 2125);
DISPLAY INVISIBLE (-2950 2125);
FORCEADD OFFPAGE..4
(-1975 2325);
FORCEPROP 2 LAST $XR1 84 
J 0
(-1699 2325);
DISPLAY 0.638298 (-1699 2325);
PAINT MONO (-1699 2325);
FORCEPROP 2 LAST $XR0 79 
J 0
(-1789 2325);
DISPLAY 0.638298 (-1789 2325);
PAINT MONO (-1789 2325);
FORCEPROP 2 LAST CDS_LIB standard
J 0
(-1975 2325);
DISPLAY INVISIBLE (-1975 2325);
FORCEPROP 1 LAST OFFPAGE TRUE
J 0
(-1650 2200);
DISPLAY 0.872340 (-1650 2200);
PAINT GREEN (-1650 2200);
DISPLAY INVISIBLE (-1650 2200);
FORCEPROP 1 LAST COMMENT_BODY TRUE
J 0
(-2000 2225);
DISPLAY 0.872340 (-2000 2225);
PAINT GREEN (-2000 2225);
DISPLAY INVISIBLE (-2000 2225);
FORCEPROP 2 LAST PATH I351
J 0
(-1775 2375);
DISPLAY 0.680851 (-1775 2375);
DISPLAY INVISIBLE (-1775 2375);
FORCEADD Q_RES..1
(-3200 2325);
FORCEPROP 1 LAST LOCATION R1742
J 0
(-3650 2325);
DISPLAY 0.489362 (-3650 2325);
PAINT SKYBLUE (-3650 2325);
FORCEPROP 0 LAST $SEC 1
J 0
(-3450 2375);
PAINT MONO (-3450 2375);
DISPLAY INVISIBLE (-3450 2375);
FORCEPROP 0 LAST CDS_SEC 1
J 0
(-3450 2375);
PAINT MONO (-3450 2375);
DISPLAY INVISIBLE (-3450 2375);
FORCEPROP 1 LASTPIN (-3300 2325) $PN 1
J 0
(-3288 2337);
DISPLAY 0.489362 (-3288 2337);
PAINT GREEN (-3288 2337);
FORCEPROP 1 LASTPIN (-3100 2325) $PN 2
J 0
(-3138 2337);
DISPLAY 0.489362 (-3138 2337);
PAINT GREEN (-3138 2337);
FORCEPROP 1 LAST MATERIAL CHIP
J 0
(-3375 2300);
DISPLAY 0.489362 (-3375 2300);
PAINT SKYBLUE (-3375 2300);
FORCEPROP 1 LAST TOLERANCE 1%
J 0
(-3100 2300);
DISPLAY 0.489362 (-3100 2300);
PAINT SKYBLUE (-3100 2300);
FORCEPROP 1 LAST VALUE 22
J 2
(-3300 2325);
DISPLAY 0.489362 (-3300 2325);
PAINT SKYBLUE (-3300 2325);
FORCEPROP 2 LAST CDS_LIB pure_quanta
J 0
(-3200 2325);
PAINT MONO (-3200 2325);
DISPLAY INVISIBLE (-3200 2325);
FORCEPROP 1 LAST PATH I352
J 0
(-3250 2475);
DISPLAY 0.978723 (-3250 2475);
PAINT WHITE (-3250 2475);
DISPLAY INVISIBLE (-3250 2475);
FORCEPROP 1 LAST WATTAGE 1/16W
J 2
(-3225 2175);
DISPLAY 0.978723 (-3225 2175);
PAINT SKYBLUE (-3225 2175);
DISPLAY INVISIBLE (-3225 2175);
FORCEPROP 1 LAST PART_NUMBER CS02202FB12
J 0
(-3250 2425);
DISPLAY 0.978723 (-3250 2425);
PAINT SKYBLUE (-3250 2425);
DISPLAY INVISIBLE (-3250 2425);
FORCEPROP 1 LAST PACK_TYPE 0402LF
J 0
(-2950 2175);
DISPLAY 0.978723 (-2950 2175);
PAINT SKYBLUE (-2950 2175);
DISPLAY INVISIBLE (-2950 2175);
FORCEADD OFFPAGE..5
R 2
(-1975 3975);
FORCEPROP 2 LAST $XR1 149 
J 0
(-1666 3975);
DISPLAY 0.638298 (-1666 3975);
PAINT MONO (-1666 3975);
FORCEPROP 2 LAST $XR0 148 
J 0
(-1786 3975);
DISPLAY 0.638298 (-1786 3975);
PAINT MONO (-1786 3975);
FORCEPROP 2 LAST CDS_LIB standard
J 0
(-1975 3975);
DISPLAY INVISIBLE (-1975 3975);
FORCEPROP 1 LAST OFFPAGE TRUE
J 2
(-2300 3850);
DISPLAY 0.872340 (-2300 3850);
PAINT GREEN (-2300 3850);
DISPLAY INVISIBLE (-2300 3850);
FORCEPROP 1 LAST COMMENT_BODY TRUE
J 2
(-2075 3900);
DISPLAY 0.872340 (-2075 3900);
PAINT GREEN (-2075 3900);
DISPLAY INVISIBLE (-2075 3900);
FORCEPROP 2 LAST PATH I355
J 0
(-1650 4025);
DISPLAY 0.680851 (-1650 4025);
DISPLAY INVISIBLE (-1650 4025);
FORCEADD Q_RES..1
(-3200 3975);
FORCEPROP 1 LAST LOCATION R1737
J 0
(-3650 3975);
DISPLAY 0.489362 (-3650 3975);
PAINT SKYBLUE (-3650 3975);
FORCEPROP 0 LAST $SEC 1
J 0
(-3525 4025);
DISPLAY 0.680851 (-3525 4025);
PAINT MONO (-3525 4025);
DISPLAY INVISIBLE (-3525 4025);
FORCEPROP 0 LAST CDS_SEC 1
J 0
(-3525 4025);
DISPLAY 1.021277 (-3525 4025);
DISPLAY INVISIBLE (-3525 4025);
FORCEPROP 1 LASTPIN (-3300 3975) $PN 1
J 0
(-3288 3987);
DISPLAY 0.489362 (-3288 3987);
PAINT MONO (-3288 3987);
FORCEPROP 1 LASTPIN (-3100 3975) $PN 2
J 0
(-3138 3987);
DISPLAY 0.489362 (-3138 3987);
PAINT MONO (-3138 3987);
FORCEPROP 1 LAST MATERIAL CHIP
J 0
(-3375 3950);
DISPLAY 0.489362 (-3375 3950);
PAINT SKYBLUE (-3375 3950);
FORCEPROP 1 LAST TOLERANCE 1%
J 0
(-3100 3950);
DISPLAY 0.489362 (-3100 3950);
PAINT SKYBLUE (-3100 3950);
FORCEPROP 1 LAST VALUE 22
J 2
(-3300 3975);
DISPLAY 0.489362 (-3300 3975);
PAINT SKYBLUE (-3300 3975);
FORCEPROP 2 LAST CDS_LIB pure_quanta
J 0
(-3200 3975);
DISPLAY INVISIBLE (-3200 3975);
FORCEPROP 1 LAST PATH I357
J 0
(-3250 4125);
DISPLAY 0.978723 (-3250 4125);
PAINT WHITE (-3250 4125);
DISPLAY INVISIBLE (-3250 4125);
FORCEPROP 1 LAST WATTAGE 1/16W
J 2
(-3225 3825);
DISPLAY 0.978723 (-3225 3825);
PAINT SKYBLUE (-3225 3825);
DISPLAY INVISIBLE (-3225 3825);
FORCEPROP 1 LAST PART_NUMBER CS02202FB12
J 0
(-3250 4075);
DISPLAY 0.978723 (-3250 4075);
PAINT SKYBLUE (-3250 4075);
DISPLAY INVISIBLE (-3250 4075);
FORCEPROP 1 LAST PACK_TYPE 0402LF
J 0
(-2950 3825);
DISPLAY 0.978723 (-2950 3825);
PAINT SKYBLUE (-2950 3825);
DISPLAY INVISIBLE (-2950 3825);
FORCEADD OFFPAGE..5
R 2
(-1975 4225);
FORCEPROP 2 LAST $XR1 149 
J 0
(-1666 4225);
DISPLAY 0.638298 (-1666 4225);
PAINT MONO (-1666 4225);
FORCEPROP 2 LAST $XR0 148 
J 0
(-1786 4225);
DISPLAY 0.638298 (-1786 4225);
PAINT MONO (-1786 4225);
FORCEPROP 2 LAST CDS_LIB standard
J 0
(-1975 4225);
DISPLAY INVISIBLE (-1975 4225);
FORCEPROP 1 LAST OFFPAGE TRUE
J 2
(-2300 4100);
DISPLAY 0.872340 (-2300 4100);
PAINT GREEN (-2300 4100);
DISPLAY INVISIBLE (-2300 4100);
FORCEPROP 1 LAST COMMENT_BODY TRUE
J 2
(-2075 4150);
DISPLAY 0.872340 (-2075 4150);
PAINT GREEN (-2075 4150);
DISPLAY INVISIBLE (-2075 4150);
FORCEPROP 2 LAST PATH I362
J 0
(-1650 4275);
DISPLAY 0.680851 (-1650 4275);
DISPLAY INVISIBLE (-1650 4275);
FORCEADD Q_RES..1
(-3200 4225);
FORCEPROP 1 LAST LOCATION R1736
J 0
(-3650 4225);
DISPLAY 0.489362 (-3650 4225);
PAINT SKYBLUE (-3650 4225);
FORCEPROP 0 LAST $SEC 1
J 0
(-3450 4275);
PAINT MONO (-3450 4275);
DISPLAY INVISIBLE (-3450 4275);
FORCEPROP 0 LAST CDS_SEC 1
J 0
(-3450 4275);
PAINT MONO (-3450 4275);
DISPLAY INVISIBLE (-3450 4275);
FORCEPROP 1 LASTPIN (-3300 4225) $PN 1
J 0
(-3288 4237);
DISPLAY 0.489362 (-3288 4237);
PAINT GREEN (-3288 4237);
FORCEPROP 1 LASTPIN (-3100 4225) $PN 2
J 0
(-3138 4237);
DISPLAY 0.489362 (-3138 4237);
PAINT GREEN (-3138 4237);
FORCEPROP 1 LAST MATERIAL CHIP
J 0
(-3375 4200);
DISPLAY 0.489362 (-3375 4200);
PAINT SKYBLUE (-3375 4200);
FORCEPROP 1 LAST TOLERANCE 1%
J 0
(-3100 4200);
DISPLAY 0.489362 (-3100 4200);
PAINT SKYBLUE (-3100 4200);
FORCEPROP 1 LAST VALUE 22
J 2
(-3300 4225);
DISPLAY 0.489362 (-3300 4225);
PAINT SKYBLUE (-3300 4225);
FORCEPROP 2 LAST CDS_LIB pure_quanta
J 0
(-3200 4225);
PAINT MONO (-3200 4225);
DISPLAY INVISIBLE (-3200 4225);
FORCEPROP 1 LAST PATH I363
J 0
(-3250 4375);
DISPLAY 0.978723 (-3250 4375);
PAINT WHITE (-3250 4375);
DISPLAY INVISIBLE (-3250 4375);
FORCEPROP 1 LAST WATTAGE 1/16W
J 2
(-3225 4075);
DISPLAY 0.978723 (-3225 4075);
PAINT SKYBLUE (-3225 4075);
DISPLAY INVISIBLE (-3225 4075);
FORCEPROP 1 LAST PART_NUMBER CS02202FB12
J 0
(-3250 4325);
DISPLAY 0.978723 (-3250 4325);
PAINT SKYBLUE (-3250 4325);
DISPLAY INVISIBLE (-3250 4325);
FORCEPROP 1 LAST PACK_TYPE 0402LF
J 0
(-2950 4075);
DISPLAY 0.978723 (-2950 4075);
PAINT SKYBLUE (-2950 4075);
DISPLAY INVISIBLE (-2950 4075);
FORCEADD OFFPAGE..5
R 2
(-1975 4025);
FORCEPROP 2 LAST $XR1 79 
J 0
(-1696 4025);
DISPLAY 0.638298 (-1696 4025);
PAINT MONO (-1696 4025);
FORCEPROP 2 LAST $XR0 84 
J 0
(-1786 4025);
DISPLAY 0.638298 (-1786 4025);
PAINT MONO (-1786 4025);
FORCEPROP 2 LAST CDS_LIB standard
J 0
(-1975 4025);
DISPLAY INVISIBLE (-1975 4025);
FORCEPROP 1 LAST OFFPAGE TRUE
J 2
(-2300 3900);
DISPLAY 0.872340 (-2300 3900);
PAINT GREEN (-2300 3900);
DISPLAY INVISIBLE (-2300 3900);
FORCEPROP 1 LAST COMMENT_BODY TRUE
J 2
(-2075 3950);
DISPLAY 0.872340 (-2075 3950);
PAINT GREEN (-2075 3950);
DISPLAY INVISIBLE (-2075 3950);
FORCEPROP 2 LAST PATH I365
J 0
(-1775 4075);
DISPLAY 0.680851 (-1775 4075);
DISPLAY INVISIBLE (-1775 4075);
FORCEADD Q_RES..1
(-3200 4025);
FORCEPROP 1 LAST LOCATION R1741
J 0
(-3650 4025);
DISPLAY 0.489362 (-3650 4025);
PAINT SKYBLUE (-3650 4025);
FORCEPROP 0 LAST $SEC 1
J 0
(-3525 4075);
DISPLAY 0.680851 (-3525 4075);
PAINT MONO (-3525 4075);
DISPLAY INVISIBLE (-3525 4075);
FORCEPROP 0 LAST CDS_SEC 1
J 0
(-3525 4075);
DISPLAY 1.021277 (-3525 4075);
DISPLAY INVISIBLE (-3525 4075);
FORCEPROP 1 LASTPIN (-3300 4025) $PN 1
J 0
(-3288 4037);
DISPLAY 0.489362 (-3288 4037);
PAINT MONO (-3288 4037);
FORCEPROP 1 LASTPIN (-3100 4025) $PN 2
J 0
(-3138 4037);
DISPLAY 0.489362 (-3138 4037);
PAINT MONO (-3138 4037);
FORCEPROP 1 LAST MATERIAL CHIP
J 0
(-3375 4000);
DISPLAY 0.489362 (-3375 4000);
PAINT SKYBLUE (-3375 4000);
FORCEPROP 1 LAST TOLERANCE 1%
J 0
(-3100 4000);
DISPLAY 0.489362 (-3100 4000);
PAINT SKYBLUE (-3100 4000);
FORCEPROP 1 LAST VALUE 22
J 2
(-3300 4025);
DISPLAY 0.489362 (-3300 4025);
PAINT SKYBLUE (-3300 4025);
FORCEPROP 2 LAST CDS_LIB pure_quanta
J 0
(-3200 4025);
DISPLAY INVISIBLE (-3200 4025);
FORCEPROP 1 LAST PATH I366
J 0
(-3250 4175);
DISPLAY 0.978723 (-3250 4175);
PAINT WHITE (-3250 4175);
DISPLAY INVISIBLE (-3250 4175);
FORCEPROP 1 LAST WATTAGE 1/16W
J 2
(-3225 3875);
DISPLAY 0.978723 (-3225 3875);
PAINT SKYBLUE (-3225 3875);
DISPLAY INVISIBLE (-3225 3875);
FORCEPROP 1 LAST PART_NUMBER CS02202FB12
J 0
(-3250 4125);
DISPLAY 0.978723 (-3250 4125);
PAINT SKYBLUE (-3250 4125);
DISPLAY INVISIBLE (-3250 4125);
FORCEPROP 1 LAST PACK_TYPE 0402LF
J 0
(-2950 3875);
DISPLAY 0.978723 (-2950 3875);
PAINT SKYBLUE (-2950 3875);
DISPLAY INVISIBLE (-2950 3875);
FORCEADD OFFPAGE..5
R 2
(-1975 4275);
FORCEPROP 2 LAST $XR1 79 
J 0
(-1696 4275);
DISPLAY 0.638298 (-1696 4275);
PAINT MONO (-1696 4275);
FORCEPROP 2 LAST $XR0 84 
J 0
(-1786 4275);
DISPLAY 0.638298 (-1786 4275);
PAINT MONO (-1786 4275);
FORCEPROP 2 LAST CDS_LIB standard
J 0
(-1975 4275);
DISPLAY INVISIBLE (-1975 4275);
FORCEPROP 1 LAST OFFPAGE TRUE
J 2
(-2300 4150);
DISPLAY 0.872340 (-2300 4150);
PAINT GREEN (-2300 4150);
DISPLAY INVISIBLE (-2300 4150);
FORCEPROP 1 LAST COMMENT_BODY TRUE
J 2
(-2075 4200);
DISPLAY 0.872340 (-2075 4200);
PAINT GREEN (-2075 4200);
DISPLAY INVISIBLE (-2075 4200);
FORCEPROP 2 LAST PATH I367
J 0
(-1775 4325);
DISPLAY 0.680851 (-1775 4325);
DISPLAY INVISIBLE (-1775 4325);
FORCEADD Q_RES..1
(-3200 4275);
FORCEPROP 1 LAST LOCATION R1740
J 0
(-3650 4275);
DISPLAY 0.489362 (-3650 4275);
PAINT SKYBLUE (-3650 4275);
FORCEPROP 0 LAST $SEC 1
J 0
(-3450 4325);
PAINT MONO (-3450 4325);
DISPLAY INVISIBLE (-3450 4325);
FORCEPROP 0 LAST CDS_SEC 1
J 0
(-3450 4325);
PAINT MONO (-3450 4325);
DISPLAY INVISIBLE (-3450 4325);
FORCEPROP 1 LASTPIN (-3300 4275) $PN 1
J 0
(-3288 4287);
DISPLAY 0.489362 (-3288 4287);
PAINT GREEN (-3288 4287);
FORCEPROP 1 LASTPIN (-3100 4275) $PN 2
J 0
(-3138 4287);
DISPLAY 0.489362 (-3138 4287);
PAINT GREEN (-3138 4287);
FORCEPROP 1 LAST MATERIAL CHIP
J 0
(-3375 4250);
DISPLAY 0.489362 (-3375 4250);
PAINT SKYBLUE (-3375 4250);
FORCEPROP 1 LAST TOLERANCE 1%
J 0
(-3100 4250);
DISPLAY 0.489362 (-3100 4250);
PAINT SKYBLUE (-3100 4250);
FORCEPROP 1 LAST VALUE 22
J 2
(-3300 4275);
DISPLAY 0.489362 (-3300 4275);
PAINT SKYBLUE (-3300 4275);
FORCEPROP 2 LAST CDS_LIB pure_quanta
J 0
(-3200 4275);
PAINT MONO (-3200 4275);
DISPLAY INVISIBLE (-3200 4275);
FORCEPROP 1 LAST PATH I368
J 0
(-3250 4425);
DISPLAY 0.978723 (-3250 4425);
PAINT WHITE (-3250 4425);
DISPLAY INVISIBLE (-3250 4425);
FORCEPROP 1 LAST WATTAGE 1/16W
J 2
(-3225 4125);
DISPLAY 0.978723 (-3225 4125);
PAINT SKYBLUE (-3225 4125);
DISPLAY INVISIBLE (-3225 4125);
FORCEPROP 1 LAST PART_NUMBER CS02202FB12
J 0
(-3250 4375);
DISPLAY 0.978723 (-3250 4375);
PAINT SKYBLUE (-3250 4375);
DISPLAY INVISIBLE (-3250 4375);
FORCEPROP 1 LAST PACK_TYPE 0402LF
J 0
(-2950 4125);
DISPLAY 0.978723 (-2950 4125);
PAINT SKYBLUE (-2950 4125);
DISPLAY INVISIBLE (-2950 4125);
FORCEADD Q_RES..2
(-8025 5025);
FORCEPROP 1 LAST LOCATION R1342
J 0
(-7980 5150);
DISPLAY 0.489362 (-7980 5150);
PAINT SKYBLUE (-7980 5150);
FORCEPROP 0 LAST $SEC 1
J 0
(-7975 5200);
DISPLAY 0.680851 (-7975 5200);
PAINT MONO (-7975 5200);
DISPLAY INVISIBLE (-7975 5200);
FORCEPROP 0 LAST CDS_SEC 1
J 0
(-7975 5200);
DISPLAY 0.680851 (-7975 5200);
DISPLAY INVISIBLE (-7975 5200);
FORCEPROP 1 LASTPIN (-8025 5125) $PN 1
J 0
(-8020 5087);
DISPLAY 0.489362 (-8020 5087);
PAINT MONO (-8020 5087);
FORCEPROP 1 LASTPIN (-8025 4925) $PN 2
J 0
(-8020 4935);
DISPLAY 0.489362 (-8020 4935);
PAINT MONO (-8020 4935);
FORCEPROP 1 LAST WATTAGE 1/16W
J 0
(-7985 5000);
DISPLAY 0.489362 (-7985 5000);
PAINT SKYBLUE (-7985 5000);
FORCEPROP 1 LAST MATERIAL CHIP
J 0
(-7985 4950);
DISPLAY 0.489362 (-7985 4950);
PAINT SKYBLUE (-7985 4950);
FORCEPROP 1 LAST TOLERANCE 1%
J 0
(-7980 5050);
DISPLAY 0.489362 (-7980 5050);
PAINT SKYBLUE (-7980 5050);
FORCEPROP 1 LAST VALUE 10K
J 0
(-7980 5100);
DISPLAY 0.489362 (-7980 5100);
PAINT SKYBLUE (-7980 5100);
FORCEPROP 1 LAST PART_NUMBER CS31002FB08
J 0
(-7985 4900);
DISPLAY 0.489362 (-7985 4900);
PAINT SKYBLUE (-7985 4900);
FORCEPROP 1 LAST PACK_TYPE 0402LF
J 0
(-7985 4850);
DISPLAY 0.489362 (-7985 4850);
PAINT SKYBLUE (-7985 4850);
FORCEPROP 2 LAST CDS_LIB pure_quanta
J 0
(-8025 5025);
DISPLAY INVISIBLE (-8025 5025);
FORCEPROP 1 LAST PATH I369
J 0
(-7975 5200);
DISPLAY 0.978723 (-7975 5200);
PAINT WHITE (-7975 5200);
DISPLAY INVISIBLE (-7975 5200);
FORCEADD UNIVERSAL_GND..1
(-8025 4750);
FORCEPROP 3 LASTPIN (-8025 4800) SIG_NAME GND\g
J 0
(-8015 4810);
DISPLAY 0.659574 (-8015 4810);
PAINT MONO (-8015 4810);
DISPLAY INVISIBLE (-8015 4810);
FORCEPROP 2 LAST CDS_LIB pure_quanta_power
J 0
(-8025 4750);
DISPLAY INVISIBLE (-8025 4750);
FORCEPROP 1 LAST PATH I370
J 0
(-7950 4750);
DISPLAY 0.872340 (-7950 4750);
PAINT AQUA (-7950 4750);
DISPLAY INVISIBLE (-7950 4750);
FORCEPROP 1 LAST HDL_POWER GND
J 1
(-8000 4675);
DISPLAY 0.872340 (-8000 4675);
PAINT GREEN (-8000 4675);
DISPLAY INVISIBLE (-8000 4675);
FORCEADD Q_RES..2
(-5725 3550);
FORCEPROP 1 LAST LOCATION R1313
J 0
(-5680 3675);
DISPLAY 0.489362 (-5680 3675);
PAINT SKYBLUE (-5680 3675);
FORCEPROP 0 LAST $SEC 1
J 0
(-5675 3700);
DISPLAY 0.680851 (-5675 3700);
PAINT MONO (-5675 3700);
DISPLAY INVISIBLE (-5675 3700);
FORCEPROP 0 LAST CDS_SEC 1
J 0
(-5675 3700);
DISPLAY 0.680851 (-5675 3700);
DISPLAY INVISIBLE (-5675 3700);
FORCEPROP 1 LASTPIN (-5725 3650) $PN 1
J 0
(-5720 3612);
DISPLAY 0.489362 (-5720 3612);
PAINT MONO (-5720 3612);
FORCEPROP 1 LASTPIN (-5725 3450) $PN 2
J 0
(-5720 3460);
DISPLAY 0.489362 (-5720 3460);
PAINT MONO (-5720 3460);
FORCEPROP 1 LAST WATTAGE 1/16W
J 0
(-5650 3500);
DISPLAY 0.489362 (-5650 3500);
PAINT SKYBLUE (-5650 3500);
FORCEPROP 1 LAST MATERIAL CHIP
J 0
(-5655 3600);
DISPLAY 0.489362 (-5655 3600);
PAINT SKYBLUE (-5655 3600);
FORCEPROP 1 LAST TOLERANCE 5%
J 0
(-5650 3550);
DISPLAY 0.489362 (-5650 3550);
PAINT SKYBLUE (-5650 3550);
FORCEPROP 1 LAST VALUE 4.7K
J 0
(-5650 3650);
DISPLAY 0.489362 (-5650 3650);
PAINT SKYBLUE (-5650 3650);
FORCEPROP 1 LAST PART_NUMBER TMP_QCS24702JB38
J 0
(-5650 3400);
DISPLAY 0.489362 (-5650 3400);
PAINT SKYBLUE (-5650 3400);
FORCEPROP 1 LAST PACK_TYPE 0402LF
J 0
(-5650 3450);
DISPLAY 0.489362 (-5650 3450);
PAINT SKYBLUE (-5650 3450);
FORCEPROP 2 LAST CDS_LIB pure_quanta
J 0
(-5725 3550);
DISPLAY INVISIBLE (-5725 3550);
FORCEPROP 1 LAST PATH I371
J 0
(-5675 3725);
DISPLAY 0.978723 (-5675 3725);
PAINT WHITE (-5675 3725);
DISPLAY INVISIBLE (-5675 3725);
FORCEADD UNIVERSAL_GND..1
(-5725 3400);
FORCEPROP 3 LASTPIN (-5725 3450) SIG_NAME GND\g
J 0
(-5715 3460);
DISPLAY 0.659574 (-5715 3460);
PAINT MONO (-5715 3460);
DISPLAY INVISIBLE (-5715 3460);
FORCEPROP 2 LAST CDS_LIB pure_quanta_power
J 0
(-5725 3400);
DISPLAY INVISIBLE (-5725 3400);
FORCEPROP 1 LAST PATH I372
J 0
(-5650 3400);
DISPLAY 0.872340 (-5650 3400);
PAINT AQUA (-5650 3400);
DISPLAY INVISIBLE (-5650 3400);
FORCEPROP 1 LAST HDL_POWER GND
J 1
(-5700 3325);
DISPLAY 0.872340 (-5700 3325);
PAINT GREEN (-5700 3325);
DISPLAY INVISIBLE (-5700 3325);
FORCEADD Q_RES..2
(-5675 1600);
FORCEPROP 1 LAST LOCATION R1318
J 0
(-5630 1725);
DISPLAY 0.489362 (-5630 1725);
PAINT SKYBLUE (-5630 1725);
FORCEPROP 0 LAST $SEC 1
J 0
(-5625 1750);
DISPLAY 0.680851 (-5625 1750);
PAINT MONO (-5625 1750);
DISPLAY INVISIBLE (-5625 1750);
FORCEPROP 0 LAST CDS_SEC 1
J 0
(-5625 1750);
DISPLAY 0.680851 (-5625 1750);
DISPLAY INVISIBLE (-5625 1750);
FORCEPROP 1 LASTPIN (-5675 1700) $PN 1
J 0
(-5670 1662);
DISPLAY 0.489362 (-5670 1662);
PAINT MONO (-5670 1662);
FORCEPROP 1 LASTPIN (-5675 1500) $PN 2
J 0
(-5670 1510);
DISPLAY 0.489362 (-5670 1510);
PAINT MONO (-5670 1510);
FORCEPROP 1 LAST WATTAGE 1/16W
J 0
(-5600 1550);
DISPLAY 0.489362 (-5600 1550);
PAINT SKYBLUE (-5600 1550);
FORCEPROP 1 LAST MATERIAL CHIP
J 0
(-5605 1650);
DISPLAY 0.489362 (-5605 1650);
PAINT SKYBLUE (-5605 1650);
FORCEPROP 1 LAST TOLERANCE 5%
J 0
(-5600 1600);
DISPLAY 0.489362 (-5600 1600);
PAINT SKYBLUE (-5600 1600);
FORCEPROP 1 LAST VALUE 4.7K
J 0
(-5600 1700);
DISPLAY 0.489362 (-5600 1700);
PAINT SKYBLUE (-5600 1700);
FORCEPROP 1 LAST PART_NUMBER TMP_QCS24702JB38
J 0
(-5600 1450);
DISPLAY 0.489362 (-5600 1450);
PAINT SKYBLUE (-5600 1450);
FORCEPROP 1 LAST PACK_TYPE 0402LF
J 0
(-5600 1500);
DISPLAY 0.489362 (-5600 1500);
PAINT SKYBLUE (-5600 1500);
FORCEPROP 2 LAST CDS_LIB pure_quanta
J 0
(-5675 1600);
DISPLAY INVISIBLE (-5675 1600);
FORCEPROP 1 LAST PATH I373
J 0
(-5625 1775);
DISPLAY 0.978723 (-5625 1775);
PAINT WHITE (-5625 1775);
DISPLAY INVISIBLE (-5625 1775);
FORCEADD UNIVERSAL_GND..1
(-5675 1450);
FORCEPROP 3 LASTPIN (-5675 1500) SIG_NAME GND\g
J 0
(-5665 1510);
DISPLAY 0.659574 (-5665 1510);
PAINT MONO (-5665 1510);
DISPLAY INVISIBLE (-5665 1510);
FORCEPROP 2 LAST CDS_LIB pure_quanta_power
J 0
(-5675 1450);
DISPLAY INVISIBLE (-5675 1450);
FORCEPROP 1 LAST PATH I374
J 0
(-5600 1450);
DISPLAY 0.872340 (-5600 1450);
PAINT AQUA (-5600 1450);
DISPLAY INVISIBLE (-5600 1450);
FORCEPROP 1 LAST HDL_POWER GND
J 1
(-5650 1375);
DISPLAY 0.872340 (-5650 1375);
PAINT GREEN (-5650 1375);
DISPLAY INVISIBLE (-5650 1375);
FORCEADD QUANTA_TITLE_BLOCK_C..1
(0 0);
FORCEPROP 0 LAST CDS_CON_LAST_MODIFIED Fri Mar 11 14:53:16 2022
J 0
(-1885 15);
DISPLAY INVISIBLE (-1885 15);
FORCEPROP 1 LAST CUSTOM_TXT_CDS <CON_LAST_MODIFIED>
J 0
(-1885 15);
DISPLAY 0.978723 (-1885 15);
FORCEPROP 2 LAST CUSTOM_TXT_CDS <XR_PAGE_TITLE>
J 0
(-7890 5250);
DISPLAY 0.638298 (-7890 5250);
PAINT PINK (-7890 5250);
DISPLAY INVISIBLE (-7890 5250);
FORCEPROP 1 LAST CUSTOM_TXT_CDS <NAME_2>
J 0
(-3175 50);
FORCEPROP 1 LAST CUSTOM_TXT_CDS <NAME_1>
J 0
(-3175 175);
FORCEPROP 1 LAST CUSTOM_TXT_CDS <Q_NUMBER>
J 0
(-1403 103);
DISPLAY 1.212766 (-1403 103);
FORCEPROP 1 LAST CUSTOM_TXT_CDS <Q_PROJ>
J 0
(-2382 102);
DISPLAY 1.212766 (-2382 102);
FORCEPROP 1 LAST CUSTOM_TXT_CDS <Q_REV>
J 0
(-184 103);
DISPLAY 1.212766 (-184 103);
FORCEPROP 1 LAST CUSTOM_TXT_CDS <CON_PAGE_NUM> OF <CON_TOTAL_PAGES>
J 0
(-446 18);
DISPLAY 0.978723 (-446 18);
FORCEPROP 1 LAST Q_DEPT BU9
J 1
(-3763 49);
DISPLAY 1.957447 (-3763 49);
PAINT GREEN (-3763 49);
FORCEPROP 1 LAST Q_TITLE JTAG - BMC MUX
J 0
(-9275 50);
DISPLAY 2.446809 (-9275 50);
PAINT GREEN (-9275 50);
FORCEPROP 1 LAST CDS_LMAN_SYM_OUTLINE -9475,6775,100,-125
J 0
(0 0);
DISPLAY 0.468085 (0 0);
PAINT GREEN (0 0);
DISPLAY INVISIBLE (0 0);
FORCEPROP 2 LAST CDS_LIB pure_quanta
J 0
(0 0);
DISPLAY INVISIBLE (0 0);
FORCEPROP 2 LAST PAGE_BORDER TRUE
J 0
(-7890 5250);
DISPLAY 0.638298 (-7890 5250);
PAINT PINK (-7890 5250);
DISPLAY INVISIBLE (-7890 5250);
FORCEPROP 1 LAST COMMENT_BODY TRUE
J 0
(12 -13);
DISPLAY 0.978723 (12 -13);
PAINT GREEN (12 -13);
DISPLAY INVISIBLE (12 -13);
FORCEPROP 2 LAST CDS_XR_PAGE_TITLE CR-148 : @T6G_MB_LIB.T6G(SCH_1):PAGE148
J 0
(-7890 5250);
DISPLAY 0.638298 (-7890 5250);
PAINT PINK (-7890 5250);
DISPLAY INVISIBLE (-7890 5250);
FORCEADD DNS..2
(-475 5500);
PAINT RED (-475 5500);
FORCEPROP 2 LAST CDS_LIB mstr_misc
J 0
(-475 5500);
PAINT MONO (-475 5500);
DISPLAY INVISIBLE (-475 5500);
FORCEPROP 1 LAST COMMENT_BODY TRUE
J 0
(-475 5500);
PAINT RED (-475 5500);
DISPLAY INVISIBLE (-475 5500);
FORCEADD DNS..2
(-7725 4125);
PAINT RED (-7725 4125);
FORCEPROP 2 LAST CDS_LIB mstr_misc
J 0
(-7725 4125);
PAINT MONO (-7725 4125);
DISPLAY INVISIBLE (-7725 4125);
FORCEPROP 1 LAST COMMENT_BODY TRUE
J 0
(-7725 4125);
PAINT RED (-7725 4125);
DISPLAY INVISIBLE (-7725 4125);
FORCEADD DNS..2
(-2875 5525);
PAINT RED (-2875 5525);
FORCEPROP 2 LAST CDS_LIB mstr_misc
J 0
(-2875 5525);
DISPLAY INVISIBLE (-2875 5525);
FORCEPROP 1 LAST COMMENT_BODY TRUE
J 0
(-2875 5525);
PAINT RED (-2875 5525);
DISPLAY INVISIBLE (-2875 5525);
FORCEADD DNS..2
(-7725 2125);
PAINT RED (-7725 2125);
FORCEPROP 2 LAST CDS_LIB mstr_misc
J 0
(-7725 2125);
DISPLAY INVISIBLE (-7725 2125);
FORCEPROP 1 LAST COMMENT_BODY TRUE
J 0
(-7725 2125);
PAINT RED (-7725 2125);
DISPLAY INVISIBLE (-7725 2125);
FORCEADD DNS..2
(-7375 5175);
PAINT RED (-7375 5175);
FORCEPROP 2 LAST CDS_LIB mstr_misc
J 0
(-7375 5175);
DISPLAY INVISIBLE (-7375 5175);
FORCEPROP 1 LAST COMMENT_BODY TRUE
J 0
(-7375 5175);
PAINT RED (-7375 5175);
DISPLAY INVISIBLE (-7375 5175);
FORCEADD DNS..2
(-6575 5425);
PAINT RED (-6575 5425);
FORCEPROP 2 LAST CDS_LIB mstr_misc
J 0
(-6575 5425);
DISPLAY INVISIBLE (-6575 5425);
FORCEPROP 1 LAST COMMENT_BODY TRUE
J 0
(-6575 5425);
PAINT RED (-6575 5425);
DISPLAY INVISIBLE (-6575 5425);
WIRE 16 -1 (-2875 5450)(-2875 5375);
WIRE 16 -1 (-450 5425)(-450 5350);
WIRE 16 -1 (-5475 4475)(-5475 4425);
WIRE 16 -1 (-7700 4325)(-7700 4250);
WIRE 16 -1 (-5475 2525)(-5475 2475);
WIRE 16 -1 (-7750 3450)(-7750 3550);
WIRE 16 -1 (-7700 2325)(-7700 2250);
WIRE 16 -1 (-7750 1450)(-7750 1550);
WIRE 16 -1 (-6575 5600)(-6575 5725);
WIRE 16 -1 (-8000 5400)(-8000 5450);
WIRE 16 -1 (-7575 5125)(-7650 5125);
WIRE 16 -1 (-7650 5125)(-7650 5000);
WIRE 16 -1 (-8025 4925)(-8025 4800);
WIRE 16 -1 (-8000 1925)(-7750 1925);
WIRE 16 -1 (-7750 1925)(-7700 1925);
WIRE 16 -1 (-7750 1750)(-7750 1925);
WIRE 16 -1 (-7700 1925)(-7700 2050);
WIRE 16 -1 (-7700 1925)(-6700 1925);
FORCEPROP 2 LAST SIG_NAME SCM_JTAG_MUX_S0
J 0
(-7160 1935);
DISPLAY 0.489362 (-7160 1935);
WIRE 16 -1 (-6700 1925)(-5150 1925);
WIRE 16 -1 (-6700 3875)(-6700 1925);
WIRE 16 -1 (-5200 3875)(-6700 3875);
WIRE 16 -1 (-8000 3925)(-7750 3925);
WIRE 16 -1 (-7750 3925)(-7700 3925);
WIRE 16 -1 (-7750 3750)(-7750 3925);
WIRE 16 -1 (-7700 3925)(-6575 3925);
FORCEPROP 2 LAST SIG_NAME SCM_JTAG_MUX_S1
J 0
(-7160 3935);
DISPLAY 0.489362 (-7160 3935);
WIRE 16 -1 (-7700 3925)(-7700 4050);
WIRE 16 -1 (-6575 5225)(-6575 3925);
WIRE 16 -1 (-6575 3925)(-5200 3925);
WIRE 16 -1 (-6575 1975)(-6575 3925);
WIRE 16 -1 (-5150 1975)(-6575 1975);
WIRE 16 -1 (-7225 5225)(-6575 5225);
WIRE 16 -1 (-6575 5225)(-6575 5400);
WIRE 16 -1 (-5675 1700)(-5675 1875);
WIRE 16 -1 (-5675 1875)(-5150 1875);
FORCEPROP 2 LAST SIG_NAME U212_EN_N
J 0
(-5585 1885);
DISPLAY 0.489362 (-5585 1885);
FORCEPROP 2 LASTPROP $XRERR UNIQUE?
J 0
(-5825 1885);
DISPLAY 0.638298 (-5825 1885);
PAINT MONO (-5825 1885);
DISPLAY INVISIBLE (-5825 1885);
WIRE 16 -1 (-4425 1875)(-4425 1825);
WIRE 16 -1 (-4500 1875)(-4425 1875);
WIRE 16 -1 (-4425 1825)(-4500 1825);
WIRE 16 -1 (-4425 1825)(-4425 1650);
WIRE 16 -1 (-5875 2325)(-5150 2325);
FORCEPROP 2 LAST SIG_NAME JTAG_SCM_TDI
J 0
(-5785 2335);
DISPLAY 0.489362 (-5785 2335);
WIRE 16 -1 (-5875 2125)(-5150 2125);
FORCEPROP 2 LAST SIG_NAME JTAG_SCM_TDO
J 0
(-5785 2135);
DISPLAY 0.489362 (-5785 2135);
WIRE 16 -1 (-5350 2800)(-5350 2375);
WIRE 16 -1 (-5350 2875)(-5350 2800);
WIRE 16 -1 (-5475 2800)(-5350 2800);
WIRE 16 -1 (-5350 2375)(-5150 2375);
WIRE 16 -1 (-5475 2725)(-5475 2800);
WIRE 16 -1 (-5725 3650)(-5725 3825);
WIRE 16 -1 (-5725 3825)(-5200 3825);
FORCEPROP 2 LAST SIG_NAME U160_EN_N
J 0
(-5635 3835);
DISPLAY 0.489362 (-5635 3835);
FORCEPROP 2 LASTPROP $XRERR UNIQUE?
J 0
(-5875 3835);
DISPLAY 0.638298 (-5875 3835);
PAINT MONO (-5875 3835);
DISPLAY INVISIBLE (-5875 3835);
WIRE 16 -1 (-5850 4075)(-5200 4075);
FORCEPROP 2 LAST SIG_NAME JTAG_SCM_TMS
J 0
(-5760 4085);
DISPLAY 0.489362 (-5760 4085);
WIRE 16 -1 (-4475 3775)(-4550 3775);
WIRE 16 -1 (-4475 3825)(-4475 3775);
WIRE 16 -1 (-4475 3775)(-4475 3575);
WIRE 16 -1 (-4550 3825)(-4475 3825);
WIRE 16 -1 (-8000 5700)(-7650 5700);
WIRE 16 -1 (-8000 5800)(-8000 5700);
WIRE 16 -1 (-8000 5700)(-8000 5650);
WIRE 16 -1 (-7650 5700)(-7650 5325);
WIRE 16 -1 (-7650 5325)(-7575 5325);
WIRE 16 -1 (-7575 5225)(-8025 5225);
WIRE 16 -1 (-8025 5225)(-8025 5125);
WIRE 16 -1 (-8025 5225)(-8950 5225);
FORCEPROP 2 LAST SIG_NAME HPM_FW_RECOVERY_R
J 0
(-8685 5250);
DISPLAY 0.489362 (-8685 5250);
WIRE 16 -1 (-5850 4275)(-5200 4275);
FORCEPROP 2 LAST SIG_NAME JTAG_SCM_TCK
J 0
(-5760 4285);
DISPLAY 0.489362 (-5760 4285);
WIRE 16 -1 (-5350 4750)(-5350 4325);
WIRE 16 -1 (-5350 4825)(-5350 4750);
WIRE 16 -1 (-5475 4750)(-5350 4750);
WIRE 16 -1 (-5350 4325)(-5200 4325);
WIRE 16 -1 (-5475 4675)(-5475 4750);
WIRE 16 -1 (-4500 2025)(-3300 2025);
FORCEPROP 2 LAST SIG_NAME JTAG_SCM_MUX_R_TDO
J 0
(-4400 2035);
DISPLAY 0.489362 (-4400 2035);
FORCEPROP 2 LASTPROP $XRERR UNIQUE?
J 0
(-4640 2035);
DISPLAY 0.638298 (-4640 2035);
PAINT MONO (-4640 2035);
DISPLAY INVISIBLE (-4640 2035);
WIRE 16 -1 (-4550 4225)(-3300 4225);
FORCEPROP 2 LAST SIG_NAME JTAG_SCM_MUX_R_TCK
J 0
(-4400 4235);
DISPLAY 0.489362 (-4400 4235);
FORCEPROP 2 LASTPROP $XRERR UNIQUE?
J 0
(-4640 4235);
DISPLAY 0.638298 (-4640 4235);
PAINT MONO (-4640 4235);
DISPLAY INVISIBLE (-4640 4235);
WIRE 16 -1 (-4550 4175)(-3300 4175);
FORCEPROP 2 LAST SIG_NAME TP_JTAG_SCM_SLOT3_R_TCK
J 0
(-4400 4185);
DISPLAY 0.489362 (-4400 4185);
FORCEPROP 2 LASTPROP $XRERR UNIQUE?
J 0
(-3270 4175);
DISPLAY 0.638298 (-3270 4175);
PAINT MONO (-3270 4175);
DISPLAY INVISIBLE (-3270 4175);
WIRE 16 -1 (-4550 3975)(-3300 3975);
FORCEPROP 2 LAST SIG_NAME JTAG_SCM_MUX_R_TMS
J 0
(-4400 3985);
DISPLAY 0.489362 (-4400 3985);
FORCEPROP 2 LASTPROP $XRERR UNIQUE?
J 0
(-4640 3985);
DISPLAY 0.638298 (-4640 3985);
PAINT MONO (-4640 3985);
DISPLAY INVISIBLE (-4640 3985);
WIRE 16 -1 (-4500 1975)(-3300 1975);
FORCEPROP 2 LAST SIG_NAME TP_JTAG_SCM_SLOT3_R_TDO
J 0
(-4400 1985);
DISPLAY 0.489362 (-4400 1985);
FORCEPROP 2 LASTPROP $XRERR UNIQUE?
J 0
(-3270 1975);
DISPLAY 0.638298 (-3270 1975);
PAINT MONO (-3270 1975);
DISPLAY INVISIBLE (-3270 1975);
WIRE 16 -1 (-4500 2275)(-3300 2275);
FORCEPROP 2 LAST SIG_NAME JTAG_SCM_MUX_R_TDI
J 0
(-4400 2285);
DISPLAY 0.489362 (-4400 2285);
FORCEPROP 2 LASTPROP $XRERR UNIQUE?
J 0
(-4640 2285);
DISPLAY 0.638298 (-4640 2285);
PAINT MONO (-4640 2285);
DISPLAY INVISIBLE (-4640 2285);
WIRE 16 -1 (-4550 3925)(-3300 3925);
FORCEPROP 2 LAST SIG_NAME TP_JTAG_SCM_SLOT3_R_TMS
J 0
(-4400 3935);
DISPLAY 0.489362 (-4400 3935);
FORCEPROP 2 LASTPROP $XRERR UNIQUE?
J 0
(-3270 3925);
DISPLAY 0.638298 (-3270 3925);
PAINT MONO (-3270 3925);
DISPLAY INVISIBLE (-3270 3925);
WIRE 16 -1 (-4500 2225)(-3300 2225);
FORCEPROP 2 LAST SIG_NAME TP_JTAG_SCM_SLOT3_R_TDI
J 0
(-4400 2235);
DISPLAY 0.489362 (-4400 2235);
FORCEPROP 2 LASTPROP $XRERR UNIQUE?
J 0
(-3270 2225);
DISPLAY 0.638298 (-3270 2225);
PAINT MONO (-3270 2225);
DISPLAY INVISIBLE (-3270 2225);
WIRE 16 -1 (-4500 2125)(-3775 2125);
WIRE 16 -1 (-3775 2125)(-3775 2075);
WIRE 16 -1 (-3775 2075)(-3300 2075);
WIRE 16 -1 (-4500 2075)(-3775 2075);
FORCEPROP 2 LAST SIG_NAME JTAG_SCM_PLD_R_TDO
J 0
(-4400 2085);
DISPLAY 0.489362 (-4400 2085);
FORCEPROP 2 LASTPROP $XRERR UNIQUE?
J 0
(-4640 2085);
DISPLAY 0.638298 (-4640 2085);
PAINT MONO (-4640 2085);
DISPLAY INVISIBLE (-4640 2085);
WIRE 16 -1 (-4500 2375)(-3725 2375);
WIRE 16 -1 (-3725 2375)(-3725 2325);
WIRE 16 -1 (-3725 2325)(-3300 2325);
WIRE 16 -1 (-4500 2325)(-3725 2325);
FORCEPROP 2 LAST SIG_NAME JTAG_SCM_PLD_R_TDI
J 0
(-4400 2335);
DISPLAY 0.489362 (-4400 2335);
FORCEPROP 2 LASTPROP $XRERR UNIQUE?
J 0
(-4640 2335);
DISPLAY 0.638298 (-4640 2335);
PAINT MONO (-4640 2335);
DISPLAY INVISIBLE (-4640 2335);
WIRE 16 -1 (-4550 4075)(-3850 4075);
WIRE 16 -1 (-3850 4075)(-3850 4025);
WIRE 16 -1 (-3850 4025)(-3300 4025);
WIRE 16 -1 (-4550 4025)(-3850 4025);
FORCEPROP 2 LAST SIG_NAME JTAG_SCM_PLD_R_TMS
J 0
(-4400 4035);
DISPLAY 0.489362 (-4400 4035);
FORCEPROP 2 LASTPROP $XRERR UNIQUE?
J 0
(-4640 4035);
DISPLAY 0.638298 (-4640 4035);
PAINT MONO (-4640 4035);
DISPLAY INVISIBLE (-4640 4035);
WIRE 16 -1 (-3100 2025)(-2025 2025);
FORCEPROP 2 LAST SIG_NAME JTAG_SCM_MUX_TDO
J 0
(-2850 2035);
DISPLAY 0.489362 (-2850 2035);
WIRE 16 -1 (-3100 2075)(-2025 2075);
FORCEPROP 2 LAST SIG_NAME JTAG_SCM_PLD_TDO
J 0
(-2850 2085);
DISPLAY 0.489362 (-2850 2085);
WIRE 16 -1 (-3100 2275)(-2025 2275);
FORCEPROP 2 LAST SIG_NAME JTAG_SCM_MUX_TDI
J 0
(-2850 2285);
DISPLAY 0.489362 (-2850 2285);
WIRE 16 -1 (-3100 2325)(-2025 2325);
FORCEPROP 2 LAST SIG_NAME JTAG_SCM_PLD_TDI
J 0
(-2850 2335);
DISPLAY 0.489362 (-2850 2335);
WIRE 16 -1 (-3100 3975)(-2025 3975);
FORCEPROP 2 LAST SIG_NAME JTAG_SCM_MUX_TMS
J 0
(-2875 3985);
DISPLAY 0.489362 (-2875 3985);
WIRE 16 -1 (-3100 4025)(-2025 4025);
FORCEPROP 2 LAST SIG_NAME JTAG_SCM_PLD_TMS
J 0
(-2885 4035);
DISPLAY 0.489362 (-2885 4035);
WIRE 16 -1 (-4550 4325)(-3825 4325);
WIRE 16 -1 (-3825 4325)(-3825 4275);
WIRE 16 -1 (-3825 4275)(-3300 4275);
WIRE 16 -1 (-4550 4275)(-3825 4275);
FORCEPROP 2 LAST SIG_NAME JTAG_SCM_PLD_R_TCK
J 0
(-4400 4285);
DISPLAY 0.489362 (-4400 4285);
FORCEPROP 2 LASTPROP $XRERR UNIQUE?
J 0
(-4640 4285);
DISPLAY 0.638298 (-4640 4285);
PAINT MONO (-4640 4285);
DISPLAY INVISIBLE (-4640 4285);
WIRE 16 -1 (-4125 5850)(-3525 5850);
FORCEPROP 2 LAST SIG_NAME JTAG_SCM_TDO
J 0
(-4060 5860);
DISPLAY 0.489362 (-4060 5860);
WIRE 16 -1 (-3525 5850)(-3525 5950);
WIRE 16 -1 (-3125 5950)(-3125 5750);
WIRE 16 -1 (-3125 5750)(-4125 5750);
FORCEPROP 2 LAST SIG_NAME JTAG_SCM_TMS
J 0
(-4060 5760);
DISPLAY 0.489362 (-4060 5760);
WIRE 16 -1 (-3325 5950)(-3325 5800);
WIRE 16 -1 (-3325 5800)(-4125 5800);
FORCEPROP 2 LAST SIG_NAME JTAG_SCM_TDI
J 0
(-4060 5810);
DISPLAY 0.489362 (-4060 5810);
WIRE 16 -1 (-2875 5950)(-2875 5700);
WIRE 16 -1 (-2875 5650)(-2875 5700);
WIRE 16 -1 (-2875 5700)(-4125 5700);
FORCEPROP 2 LAST SIG_NAME JTAG_SCM_TCK
J 0
(-4060 5710);
DISPLAY 0.489362 (-4060 5710);
WIRE 16 -1 (-3525 6250)(-3325 6250);
WIRE 16 -1 (-3525 6350)(-3525 6250);
WIRE 16 -1 (-3525 6250)(-3525 6150);
WIRE 16 -1 (-3325 6250)(-3125 6250);
WIRE 16 -1 (-3325 6150)(-3325 6250);
WIRE 16 -1 (-3125 6250)(-2875 6250);
WIRE 16 -1 (-3125 6250)(-3125 6150);
WIRE 16 -1 (-2875 6250)(-2875 6150);
WIRE 16 -1 (-3100 4225)(-2025 4225);
FORCEPROP 2 LAST SIG_NAME JTAG_SCM_MUX_TCK
J 0
(-2875 4235);
DISPLAY 0.489362 (-2875 4235);
WIRE 16 -1 (-3100 4275)(-2025 4275);
FORCEPROP 2 LAST SIG_NAME JTAG_SCM_PLD_TCK
J 0
(-2885 4285);
DISPLAY 0.489362 (-2885 4285);
WIRE 16 -1 (-1950 5825)(-1075 5825);
FORCEPROP 2 LAST SIG_NAME JTAG_SCM_MUX_TDI
J 0
(-1885 5835);
DISPLAY 0.489362 (-1885 5835);
WIRE 16 -1 (-1075 5825)(-1075 5925);
WIRE 16 -1 (-875 5925)(-875 5775);
WIRE 16 -1 (-875 5775)(-1950 5775);
FORCEPROP 2 LAST SIG_NAME JTAG_SCM_MUX_TDO
J 0
(-1885 5785);
DISPLAY 0.489362 (-1885 5785);
WIRE 16 -1 (-675 5925)(-675 5725);
WIRE 16 -1 (-675 5725)(-1950 5725);
FORCEPROP 2 LAST SIG_NAME JTAG_SCM_MUX_TMS
J 0
(-1885 5735);
DISPLAY 0.489362 (-1885 5735);
WIRE 16 -1 (-450 5925)(-450 5675);
WIRE 16 -1 (-450 5625)(-450 5675);
WIRE 16 -1 (-450 5675)(-1950 5675);
FORCEPROP 2 LAST SIG_NAME JTAG_SCM_MUX_TCK
J 0
(-1885 5685);
DISPLAY 0.489362 (-1885 5685);
WIRE 16 -1 (-1075 6225)(-875 6225);
WIRE 16 -1 (-1075 6325)(-1075 6225);
WIRE 16 -1 (-1075 6225)(-1075 6125);
WIRE 16 -1 (-875 6125)(-875 6225);
WIRE 16 -1 (-875 6225)(-675 6225);
WIRE 16 -1 (-675 6225)(-450 6225);
WIRE 16 -1 (-675 6225)(-675 6125);
WIRE 16 -1 (-450 6225)(-450 6125);
DOT 1 (-1075 6225);
DOT 1 (-5350 4750);
DOT 1 (-6575 3925);
DOT 1 (-7750 3925);
DOT 1 (-7700 3925);
DOT 1 (-4475 3775);
DOT 1 (-4425 1825);
DOT 1 (-5350 2800);
DOT 1 (-6700 1925);
DOT 1 (-7750 1925);
DOT 1 (-7700 1925);
DOT 1 (-675 6225);
DOT 1 (-450 5675);
DOT 1 (-875 6225);
DOT 1 (-3525 6250);
DOT 1 (-3125 6250);
DOT 1 (-3325 6250);
DOT 1 (-2875 5700);
DOT 1 (-8000 5700);
DOT 1 (-3825 4275);
DOT 1 (-3850 4025);
DOT 1 (-3725 2325);
DOT 1 (-8025 5225);
DOT 1 (-6575 5225);
DOT 1 (-3775 2075);
FORCENOTE
CPLD
(-1725 775) 0;
DISPLAY LEFT (-1725 775);
DISPLAY 1.574468 (-1725 775);
PAINT MONO (-1725 775);
FORCENOTE
CPU
(-1725 925) 0;
DISPLAY LEFT (-1725 925);
DISPLAY 1.574468 (-1725 925);
PAINT MONO (-1725 925);
FORCENOTE
RISER SLOT3(RSVD)
(-1725 1100) 0;
DISPLAY LEFT (-1725 1100);
DISPLAY 1.574468 (-1725 1100);
PAINT MONO (-1725 1100);
FORCENOTE
CPLD
(-1725 625) 0;
DISPLAY LEFT (-1725 625);
DISPLAY 1.574468 (-1725 625);
PAINT MONO (-1725 625);
FORCENOTE
$CDS_IMAGE|table.jpg|3544|1096
(-3575 950) 0;
DISPLAY LEFT (-3575 950);
QUIT
